FILE_TYPE = MACRO_DRAWING;
SET COLOR_WIRE YELLOW;
SET COLOR_PROP ORANGE;
SET COLOR_DOT WHITE;
SET COLOR_ARC YELLOW;
SET COLOR_BODY GREEN;
SET COLOR_NOTE PURPLE;
SET PROP_DISPLAY VALUE;
SET PAGE_NUMBER P31;
FORCEADD SOCKET4677_AZIF0045P001C01CS..21
(2100 3125);
FORCEPROP 1 LAST PART_NUMBER DGA^7000023
J 0
(1050 4175);
DISPLAY 0.723404 (1050 4175);
PAINT GREEN (1050 4175);
DISPLAY INVISIBLE (1050 4175);
FORCEPROP 2 LAST VALUE SOCKET4677_AZIF0045-P001C01CS
J 0
(1050 4300);
DISPLAY 1.021277 (1050 4300);
FORCEPROP 1 LAST MATERIAL IO
J 0
(1050 4100);
DISPLAY 0.723404 (1050 4100);
PAINT GREEN (1050 4100);
FORCEPROP 2 LAST PART_TYPE SMLF
J 0
(1050 4350);
DISPLAY 1.021277 (1050 4350);
FORCEPROP 1 LAST $LOCATION U2
J 0
(1050 4250);
DISPLAY 0.723404 (1050 4250);
PAINT GREEN (1050 4250);
FORCEPROP 0 LASTPIN (900 2325) $PN J90
J 2
(890 2335);
DISPLAY 0.680851 (890 2335);
PAINT MONO (890 2335);
FORCEPROP 0 LASTPIN (900 2375) $PN P89
J 2
(890 2385);
DISPLAY 0.680851 (890 2385);
PAINT MONO (890 2385);
FORCEPROP 0 LASTPIN (900 2425) $PN T91
J 2
(890 2435);
DISPLAY 0.680851 (890 2435);
PAINT MONO (890 2435);
FORCEPROP 0 LASTPIN (900 2475) $PN V89
J 2
(890 2485);
DISPLAY 0.680851 (890 2485);
PAINT MONO (890 2485);
FORCEPROP 0 LASTPIN (900 2525) $PN Y91
J 2
(890 2535);
DISPLAY 0.680851 (890 2535);
PAINT MONO (890 2535);
FORCEPROP 0 LASTPIN (900 2575) $PN AB89
J 2
(890 2585);
DISPLAY 0.680851 (890 2585);
PAINT MONO (890 2585);
FORCEPROP 0 LASTPIN (900 2625) $PN AD91
J 2
(890 2635);
DISPLAY 0.680851 (890 2635);
PAINT MONO (890 2635);
FORCEPROP 0 LASTPIN (900 2675) $PN AF89
J 2
(890 2685);
DISPLAY 0.680851 (890 2685);
PAINT MONO (890 2685);
FORCEPROP 0 LASTPIN (900 2725) $PN AH91
J 2
(890 2735);
DISPLAY 0.680851 (890 2735);
PAINT MONO (890 2735);
FORCEPROP 0 LASTPIN (900 2775) $PN AK89
J 2
(890 2785);
DISPLAY 0.680851 (890 2785);
PAINT MONO (890 2785);
FORCEPROP 0 LASTPIN (900 2825) $PN AM91
J 2
(890 2835);
DISPLAY 0.680851 (890 2835);
PAINT MONO (890 2835);
FORCEPROP 0 LASTPIN (900 2875) $PN AP89
J 2
(890 2885);
DISPLAY 0.680851 (890 2885);
PAINT MONO (890 2885);
FORCEPROP 0 LASTPIN (900 2925) $PN AT91
J 2
(890 2935);
DISPLAY 0.680851 (890 2935);
PAINT MONO (890 2935);
FORCEPROP 0 LASTPIN (900 2975) $PN AV89
J 2
(890 2985);
DISPLAY 0.680851 (890 2985);
PAINT MONO (890 2985);
FORCEPROP 0 LASTPIN (900 3025) $PN AY91
J 2
(890 3035);
DISPLAY 0.680851 (890 3035);
PAINT MONO (890 3035);
FORCEPROP 0 LASTPIN (900 3075) $PN BB89
J 2
(890 3085);
DISPLAY 0.680851 (890 3085);
PAINT MONO (890 3085);
FORCEPROP 0 LASTPIN (900 3175) $PN K89
J 2
(890 3185);
DISPLAY 0.680851 (890 3185);
PAINT MONO (890 3185);
FORCEPROP 0 LASTPIN (900 3225) $PN N90
J 2
(890 3235);
DISPLAY 0.680851 (890 3235);
PAINT MONO (890 3235);
FORCEPROP 0 LASTPIN (900 3275) $PN R90
J 2
(890 3285);
DISPLAY 0.680851 (890 3285);
PAINT MONO (890 3285);
FORCEPROP 0 LASTPIN (900 3325) $PN U90
J 2
(890 3335);
DISPLAY 0.680851 (890 3335);
PAINT MONO (890 3335);
FORCEPROP 0 LASTPIN (900 3375) $PN W90
J 2
(890 3385);
DISPLAY 0.680851 (890 3385);
PAINT MONO (890 3385);
FORCEPROP 0 LASTPIN (900 3425) $PN AA90
J 2
(890 3435);
DISPLAY 0.680851 (890 3435);
PAINT MONO (890 3435);
FORCEPROP 0 LASTPIN (900 3475) $PN AC90
J 2
(890 3485);
DISPLAY 0.680851 (890 3485);
PAINT MONO (890 3485);
FORCEPROP 0 LASTPIN (900 3525) $PN AE90
J 2
(890 3535);
DISPLAY 0.680851 (890 3535);
PAINT MONO (890 3535);
FORCEPROP 0 LASTPIN (900 3575) $PN AG90
J 2
(890 3585);
DISPLAY 0.680851 (890 3585);
PAINT MONO (890 3585);
FORCEPROP 0 LASTPIN (900 3625) $PN AJ90
J 2
(890 3635);
DISPLAY 0.680851 (890 3635);
PAINT MONO (890 3635);
FORCEPROP 0 LASTPIN (900 3675) $PN AL90
J 2
(890 3685);
DISPLAY 0.680851 (890 3685);
PAINT MONO (890 3685);
FORCEPROP 0 LASTPIN (900 3725) $PN AN90
J 2
(890 3735);
DISPLAY 0.680851 (890 3735);
PAINT MONO (890 3735);
FORCEPROP 0 LASTPIN (900 3775) $PN AR90
J 2
(890 3785);
DISPLAY 0.680851 (890 3785);
PAINT MONO (890 3785);
FORCEPROP 0 LASTPIN (900 3825) $PN AU90
J 2
(890 3835);
DISPLAY 0.680851 (890 3835);
PAINT MONO (890 3835);
FORCEPROP 0 LASTPIN (900 3875) $PN AW90
J 2
(890 3885);
DISPLAY 0.680851 (890 3885);
PAINT MONO (890 3885);
FORCEPROP 0 LASTPIN (900 3925) $PN BA90
J 2
(890 3935);
DISPLAY 0.680851 (890 3935);
PAINT MONO (890 3935);
FORCEPROP 0 LASTPIN (3300 2325) $PN L86
J 0
(3310 2335);
DISPLAY 0.680851 (3310 2335);
PAINT MONO (3310 2335);
FORCEPROP 0 LASTPIN (3300 2375) $PN P85
J 0
(3310 2385);
DISPLAY 0.680851 (3310 2385);
PAINT MONO (3310 2385);
FORCEPROP 0 LASTPIN (3300 2425) $PN R86
J 0
(3310 2435);
DISPLAY 0.680851 (3310 2435);
PAINT MONO (3310 2435);
FORCEPROP 0 LASTPIN (3300 2475) $PN U86
J 0
(3310 2485);
DISPLAY 0.680851 (3310 2485);
PAINT MONO (3310 2485);
FORCEPROP 0 LASTPIN (3300 2525) $PN W86
J 0
(3310 2535);
DISPLAY 0.680851 (3310 2535);
PAINT MONO (3310 2535);
FORCEPROP 0 LASTPIN (3300 2575) $PN AA86
J 0
(3310 2585);
DISPLAY 0.680851 (3310 2585);
PAINT MONO (3310 2585);
FORCEPROP 0 LASTPIN (3300 2625) $PN AC86
J 0
(3310 2635);
DISPLAY 0.680851 (3310 2635);
PAINT MONO (3310 2635);
FORCEPROP 0 LASTPIN (3300 2675) $PN AE86
J 0
(3310 2685);
DISPLAY 0.680851 (3310 2685);
PAINT MONO (3310 2685);
FORCEPROP 0 LASTPIN (3300 2725) $PN AG86
J 0
(3310 2735);
DISPLAY 0.680851 (3310 2735);
PAINT MONO (3310 2735);
FORCEPROP 0 LASTPIN (3300 2775) $PN AJ86
J 0
(3310 2785);
DISPLAY 0.680851 (3310 2785);
PAINT MONO (3310 2785);
FORCEPROP 0 LASTPIN (3300 2825) $PN AL86
J 0
(3310 2835);
DISPLAY 0.680851 (3310 2835);
PAINT MONO (3310 2835);
FORCEPROP 0 LASTPIN (3300 2875) $PN AP85
J 0
(3310 2885);
DISPLAY 0.680851 (3310 2885);
PAINT MONO (3310 2885);
FORCEPROP 0 LASTPIN (3300 2925) $PN AR86
J 0
(3310 2935);
DISPLAY 0.680851 (3310 2935);
PAINT MONO (3310 2935);
FORCEPROP 0 LASTPIN (3300 2975) $PN AU86
J 0
(3310 2985);
DISPLAY 0.680851 (3310 2985);
PAINT MONO (3310 2985);
FORCEPROP 0 LASTPIN (3300 3025) $PN AW86
J 0
(3310 3035);
DISPLAY 0.680851 (3310 3035);
PAINT MONO (3310 3035);
FORCEPROP 0 LASTPIN (3300 3075) $PN BA86
J 0
(3310 3085);
DISPLAY 0.680851 (3310 3085);
PAINT MONO (3310 3085);
FORCEPROP 0 LASTPIN (3300 3175) $PN M87
J 0
(3310 3185);
DISPLAY 0.680851 (3310 3185);
PAINT MONO (3310 3185);
FORCEPROP 0 LASTPIN (3300 3225) $PN N86
J 0
(3310 3235);
DISPLAY 0.680851 (3310 3235);
PAINT MONO (3310 3235);
FORCEPROP 0 LASTPIN (3300 3275) $PN T87
J 0
(3310 3285);
DISPLAY 0.680851 (3310 3285);
PAINT MONO (3310 3285);
FORCEPROP 0 LASTPIN (3300 3325) $PN V85
J 0
(3310 3335);
DISPLAY 0.680851 (3310 3335);
PAINT MONO (3310 3335);
FORCEPROP 0 LASTPIN (3300 3375) $PN Y87
J 0
(3310 3385);
DISPLAY 0.680851 (3310 3385);
PAINT MONO (3310 3385);
FORCEPROP 0 LASTPIN (3300 3425) $PN AB85
J 0
(3310 3435);
DISPLAY 0.680851 (3310 3435);
PAINT MONO (3310 3435);
FORCEPROP 0 LASTPIN (3300 3475) $PN AD87
J 0
(3310 3485);
DISPLAY 0.680851 (3310 3485);
PAINT MONO (3310 3485);
FORCEPROP 0 LASTPIN (3300 3525) $PN AF85
J 0
(3310 3535);
DISPLAY 0.680851 (3310 3535);
PAINT MONO (3310 3535);
FORCEPROP 0 LASTPIN (3300 3575) $PN AH87
J 0
(3310 3585);
DISPLAY 0.680851 (3310 3585);
PAINT MONO (3310 3585);
FORCEPROP 0 LASTPIN (3300 3625) $PN AK85
J 0
(3310 3635);
DISPLAY 0.680851 (3310 3635);
PAINT MONO (3310 3635);
FORCEPROP 0 LASTPIN (3300 3675) $PN AM87
J 0
(3310 3685);
DISPLAY 0.680851 (3310 3685);
PAINT MONO (3310 3685);
FORCEPROP 0 LASTPIN (3300 3725) $PN AN86
J 0
(3310 3735);
DISPLAY 0.680851 (3310 3735);
PAINT MONO (3310 3735);
FORCEPROP 0 LASTPIN (3300 3775) $PN AT87
J 0
(3310 3785);
DISPLAY 0.680851 (3310 3785);
PAINT MONO (3310 3785);
FORCEPROP 0 LASTPIN (3300 3825) $PN AV85
J 0
(3310 3835);
DISPLAY 0.680851 (3310 3835);
PAINT MONO (3310 3835);
FORCEPROP 0 LASTPIN (3300 3875) $PN AY87
J 0
(3310 3885);
DISPLAY 0.680851 (3310 3885);
PAINT MONO (3310 3885);
FORCEPROP 0 LASTPIN (3300 3925) $PN BB85
J 0
(3310 3935);
DISPLAY 0.680851 (3310 3935);
PAINT MONO (3310 3935);
FORCEPROP 1 LAST CDS_LMAN_SYM_OUTLINE -1050,950,1050,-950
J 0
(2100 3125);
DISPLAY 0.468085 (2100 3125);
PAINT GREEN (2100 3125);
DISPLAY INVISIBLE (2100 3125);
FORCEPROP 1 LAST NEEDS_NO_SIZE TRUE
J 0
(2100 3125);
DISPLAY 0.723404 (2100 3125);
PAINT GREEN (2100 3125);
DISPLAY INVISIBLE (2100 3125);
FORCEPROP 2 LAST CDS_LIB pure_quanta
J 0
(2100 3125);
DISPLAY INVISIBLE (2100 3125);
FORCEPROP 2 LAST CDS_LOCATION U2
J 0
(1050 4400);
DISPLAY 1.021277 (1050 4400);
DISPLAY INVISIBLE (1050 4400);
FORCEPROP 0 LAST $SEC 21
J 0
(1050 4400);
DISPLAY 0.680851 (1050 4400);
PAINT MONO (1050 4400);
DISPLAY INVISIBLE (1050 4400);
FORCEPROP 2 LAST CDS_SEC 21
J 0
(1050 4400);
DISPLAY 1.021277 (1050 4400);
DISPLAY INVISIBLE (1050 4400);
FORCEPROP 1 LAST PATH I139
J 0
(2100 3125);
DISPLAY 0.723404 (2100 3125);
PAINT GREEN (2100 3125);
DISPLAY INVISIBLE (2100 3125);
FORCEADD TAP..1
(3825 2325);
FORCEPROP 3 LASTPIN (3775 2325) SIG_NAME P5E_CPU0_PE4_TX_DN<0>
J 0
(3785 2335);
DISPLAY 0.659574 (3785 2335);
PAINT MONO (3785 2335);
DISPLAY INVISIBLE (3785 2335);
FORCEPROP 1 LASTPIN (3775 2325) BN 0
J 0
(3763 2333);
DISPLAY 0.680851 (3763 2333);
PAINT GREEN (3763 2333);
FORCEPROP 2 LAST CDS_LIB standard
J 0
(3825 2325);
PAINT MONO (3825 2325);
DISPLAY INVISIBLE (3825 2325);
FORCEPROP 1 LAST BODY_TYPE PLUMBING
J 0
(3825 2375);
DISPLAY 0.872340 (3825 2375);
PAINT GREEN (3825 2375);
DISPLAY INVISIBLE (3825 2375);
FORCEPROP 1 LAST HDL_TAP TRUE
J 0
(4150 2200);
DISPLAY 0.872340 (4150 2200);
DISPLAY INVISIBLE (4150 2200);
FORCEPROP 1 LAST PATH I207
J 0
(3823 2325);
DISPLAY 0.872340 (3823 2325);
PAINT GREEN (3823 2325);
DISPLAY INVISIBLE (3823 2325);
FORCEADD TAP..1
(3825 2375);
FORCEPROP 3 LASTPIN (3775 2375) SIG_NAME P5E_CPU0_PE4_TX_DN<1>
J 0
(3785 2385);
DISPLAY 0.659574 (3785 2385);
PAINT MONO (3785 2385);
DISPLAY INVISIBLE (3785 2385);
FORCEPROP 1 LASTPIN (3775 2375) BN 1
J 0
(3763 2383);
DISPLAY 0.680851 (3763 2383);
PAINT GREEN (3763 2383);
FORCEPROP 2 LAST CDS_LIB standard
J 0
(3825 2375);
PAINT MONO (3825 2375);
DISPLAY INVISIBLE (3825 2375);
FORCEPROP 1 LAST BODY_TYPE PLUMBING
J 0
(3825 2425);
DISPLAY 0.872340 (3825 2425);
PAINT GREEN (3825 2425);
DISPLAY INVISIBLE (3825 2425);
FORCEPROP 1 LAST HDL_TAP TRUE
J 0
(4150 2250);
DISPLAY 0.872340 (4150 2250);
DISPLAY INVISIBLE (4150 2250);
FORCEPROP 1 LAST PATH I208
J 0
(3823 2375);
DISPLAY 0.872340 (3823 2375);
PAINT GREEN (3823 2375);
DISPLAY INVISIBLE (3823 2375);
FORCEADD TAP..1
(3825 2475);
FORCEPROP 3 LASTPIN (3775 2475) SIG_NAME P5E_CPU0_PE4_TX_DN<3>
J 0
(3785 2485);
DISPLAY 0.659574 (3785 2485);
PAINT MONO (3785 2485);
DISPLAY INVISIBLE (3785 2485);
FORCEPROP 1 LASTPIN (3775 2475) BN 3
J 0
(3763 2483);
DISPLAY 0.680851 (3763 2483);
PAINT GREEN (3763 2483);
FORCEPROP 2 LAST CDS_LIB standard
J 0
(3825 2475);
PAINT MONO (3825 2475);
DISPLAY INVISIBLE (3825 2475);
FORCEPROP 1 LAST BODY_TYPE PLUMBING
J 0
(3825 2525);
DISPLAY 0.872340 (3825 2525);
PAINT GREEN (3825 2525);
DISPLAY INVISIBLE (3825 2525);
FORCEPROP 1 LAST HDL_TAP TRUE
J 0
(4150 2350);
DISPLAY 0.872340 (4150 2350);
DISPLAY INVISIBLE (4150 2350);
FORCEPROP 1 LAST PATH I209
J 0
(3823 2475);
DISPLAY 0.872340 (3823 2475);
PAINT GREEN (3823 2475);
DISPLAY INVISIBLE (3823 2475);
FORCEADD TAP..1
(3825 2425);
FORCEPROP 3 LASTPIN (3775 2425) SIG_NAME P5E_CPU0_PE4_TX_DN<2>
J 0
(3785 2435);
DISPLAY 0.659574 (3785 2435);
PAINT MONO (3785 2435);
DISPLAY INVISIBLE (3785 2435);
FORCEPROP 1 LASTPIN (3775 2425) BN 2
J 0
(3763 2433);
DISPLAY 0.680851 (3763 2433);
PAINT GREEN (3763 2433);
FORCEPROP 2 LAST CDS_LIB standard
J 0
(3825 2425);
PAINT MONO (3825 2425);
DISPLAY INVISIBLE (3825 2425);
FORCEPROP 1 LAST BODY_TYPE PLUMBING
J 0
(3825 2475);
DISPLAY 0.872340 (3825 2475);
PAINT GREEN (3825 2475);
DISPLAY INVISIBLE (3825 2475);
FORCEPROP 1 LAST HDL_TAP TRUE
J 0
(4150 2300);
DISPLAY 0.872340 (4150 2300);
DISPLAY INVISIBLE (4150 2300);
FORCEPROP 1 LAST PATH I210
J 0
(3823 2425);
DISPLAY 0.872340 (3823 2425);
PAINT GREEN (3823 2425);
DISPLAY INVISIBLE (3823 2425);
FORCEADD TAP..1
(3825 2525);
FORCEPROP 3 LASTPIN (3775 2525) SIG_NAME P5E_CPU0_PE4_TX_DN<4>
J 0
(3785 2535);
DISPLAY 0.659574 (3785 2535);
PAINT MONO (3785 2535);
DISPLAY INVISIBLE (3785 2535);
FORCEPROP 1 LASTPIN (3775 2525) BN 4
J 0
(3763 2533);
DISPLAY 0.680851 (3763 2533);
PAINT GREEN (3763 2533);
FORCEPROP 2 LAST CDS_LIB standard
J 0
(3825 2525);
PAINT MONO (3825 2525);
DISPLAY INVISIBLE (3825 2525);
FORCEPROP 1 LAST BODY_TYPE PLUMBING
J 0
(3825 2575);
DISPLAY 0.872340 (3825 2575);
PAINT GREEN (3825 2575);
DISPLAY INVISIBLE (3825 2575);
FORCEPROP 1 LAST HDL_TAP TRUE
J 0
(4150 2400);
DISPLAY 0.872340 (4150 2400);
DISPLAY INVISIBLE (4150 2400);
FORCEPROP 1 LAST PATH I211
J 0
(3823 2525);
DISPLAY 0.872340 (3823 2525);
PAINT GREEN (3823 2525);
DISPLAY INVISIBLE (3823 2525);
FORCEADD TAP..1
(3825 2575);
FORCEPROP 3 LASTPIN (3775 2575) SIG_NAME P5E_CPU0_PE4_TX_DN<5>
J 0
(3785 2585);
DISPLAY 0.659574 (3785 2585);
PAINT MONO (3785 2585);
DISPLAY INVISIBLE (3785 2585);
FORCEPROP 1 LASTPIN (3775 2575) BN 5
J 0
(3763 2583);
DISPLAY 0.680851 (3763 2583);
PAINT GREEN (3763 2583);
FORCEPROP 2 LAST CDS_LIB standard
J 0
(3825 2575);
PAINT MONO (3825 2575);
DISPLAY INVISIBLE (3825 2575);
FORCEPROP 1 LAST BODY_TYPE PLUMBING
J 0
(3825 2625);
DISPLAY 0.872340 (3825 2625);
PAINT GREEN (3825 2625);
DISPLAY INVISIBLE (3825 2625);
FORCEPROP 1 LAST HDL_TAP TRUE
J 0
(4150 2450);
DISPLAY 0.872340 (4150 2450);
DISPLAY INVISIBLE (4150 2450);
FORCEPROP 1 LAST PATH I212
J 0
(3823 2575);
DISPLAY 0.872340 (3823 2575);
PAINT GREEN (3823 2575);
DISPLAY INVISIBLE (3823 2575);
FORCEADD TAP..1
(3825 2625);
FORCEPROP 3 LASTPIN (3775 2625) SIG_NAME P5E_CPU0_PE4_TX_DN<6>
J 0
(3785 2635);
DISPLAY 0.659574 (3785 2635);
PAINT MONO (3785 2635);
DISPLAY INVISIBLE (3785 2635);
FORCEPROP 1 LASTPIN (3775 2625) BN 6
J 0
(3763 2633);
DISPLAY 0.680851 (3763 2633);
PAINT GREEN (3763 2633);
FORCEPROP 2 LAST CDS_LIB standard
J 0
(3825 2625);
PAINT MONO (3825 2625);
DISPLAY INVISIBLE (3825 2625);
FORCEPROP 1 LAST BODY_TYPE PLUMBING
J 0
(3825 2675);
DISPLAY 0.872340 (3825 2675);
PAINT GREEN (3825 2675);
DISPLAY INVISIBLE (3825 2675);
FORCEPROP 1 LAST HDL_TAP TRUE
J 0
(4150 2500);
DISPLAY 0.872340 (4150 2500);
DISPLAY INVISIBLE (4150 2500);
FORCEPROP 1 LAST PATH I213
J 0
(3823 2625);
DISPLAY 0.872340 (3823 2625);
PAINT GREEN (3823 2625);
DISPLAY INVISIBLE (3823 2625);
FORCEADD TAP..1
(3825 2725);
FORCEPROP 3 LASTPIN (3775 2725) SIG_NAME P5E_CPU0_PE4_TX_DN<8>
J 0
(3785 2735);
DISPLAY 0.659574 (3785 2735);
PAINT MONO (3785 2735);
DISPLAY INVISIBLE (3785 2735);
FORCEPROP 1 LASTPIN (3775 2725) BN 8
J 0
(3763 2733);
DISPLAY 0.680851 (3763 2733);
PAINT GREEN (3763 2733);
FORCEPROP 2 LAST CDS_LIB standard
J 0
(3825 2725);
PAINT MONO (3825 2725);
DISPLAY INVISIBLE (3825 2725);
FORCEPROP 1 LAST BODY_TYPE PLUMBING
J 0
(3825 2775);
DISPLAY 0.872340 (3825 2775);
PAINT GREEN (3825 2775);
DISPLAY INVISIBLE (3825 2775);
FORCEPROP 1 LAST HDL_TAP TRUE
J 0
(4150 2600);
DISPLAY 0.872340 (4150 2600);
DISPLAY INVISIBLE (4150 2600);
FORCEPROP 1 LAST PATH I214
J 0
(3823 2725);
DISPLAY 0.872340 (3823 2725);
PAINT GREEN (3823 2725);
DISPLAY INVISIBLE (3823 2725);
FORCEADD TAP..1
(3825 2675);
FORCEPROP 3 LASTPIN (3775 2675) SIG_NAME P5E_CPU0_PE4_TX_DN<7>
J 0
(3785 2685);
DISPLAY 0.659574 (3785 2685);
PAINT MONO (3785 2685);
DISPLAY INVISIBLE (3785 2685);
FORCEPROP 1 LASTPIN (3775 2675) BN 7
J 0
(3763 2683);
DISPLAY 0.680851 (3763 2683);
PAINT GREEN (3763 2683);
FORCEPROP 2 LAST CDS_LIB standard
J 0
(3825 2675);
PAINT MONO (3825 2675);
DISPLAY INVISIBLE (3825 2675);
FORCEPROP 1 LAST BODY_TYPE PLUMBING
J 0
(3825 2725);
DISPLAY 0.872340 (3825 2725);
PAINT GREEN (3825 2725);
DISPLAY INVISIBLE (3825 2725);
FORCEPROP 1 LAST HDL_TAP TRUE
J 0
(4150 2550);
DISPLAY 0.872340 (4150 2550);
DISPLAY INVISIBLE (4150 2550);
FORCEPROP 1 LAST PATH I215
J 0
(3823 2675);
DISPLAY 0.872340 (3823 2675);
PAINT GREEN (3823 2675);
DISPLAY INVISIBLE (3823 2675);
FORCEADD TAP..1
(3825 2775);
FORCEPROP 3 LASTPIN (3775 2775) SIG_NAME P5E_CPU0_PE4_TX_DN<9>
J 0
(3785 2785);
DISPLAY 0.659574 (3785 2785);
PAINT MONO (3785 2785);
DISPLAY INVISIBLE (3785 2785);
FORCEPROP 1 LASTPIN (3775 2775) BN 9
J 0
(3763 2783);
DISPLAY 0.680851 (3763 2783);
PAINT GREEN (3763 2783);
FORCEPROP 2 LAST CDS_LIB standard
J 0
(3825 2775);
DISPLAY INVISIBLE (3825 2775);
FORCEPROP 1 LAST BODY_TYPE PLUMBING
J 0
(3825 2825);
DISPLAY 0.872340 (3825 2825);
PAINT GREEN (3825 2825);
DISPLAY INVISIBLE (3825 2825);
FORCEPROP 1 LAST HDL_TAP TRUE
J 0
(4150 2650);
DISPLAY 0.872340 (4150 2650);
DISPLAY INVISIBLE (4150 2650);
FORCEPROP 1 LAST PATH I216
J 0
(3823 2775);
DISPLAY 0.872340 (3823 2775);
PAINT GREEN (3823 2775);
DISPLAY INVISIBLE (3823 2775);
FORCEADD TAP..1
(3825 2825);
FORCEPROP 3 LASTPIN (3775 2825) SIG_NAME P5E_CPU0_PE4_TX_DN<10>
J 0
(3785 2835);
DISPLAY 0.659574 (3785 2835);
PAINT MONO (3785 2835);
DISPLAY INVISIBLE (3785 2835);
FORCEPROP 1 LASTPIN (3775 2825) BN 10
J 0
(3763 2833);
DISPLAY 0.680851 (3763 2833);
PAINT GREEN (3763 2833);
FORCEPROP 2 LAST CDS_LIB standard
J 0
(3825 2825);
DISPLAY INVISIBLE (3825 2825);
FORCEPROP 1 LAST BODY_TYPE PLUMBING
J 0
(3825 2875);
DISPLAY 0.872340 (3825 2875);
PAINT GREEN (3825 2875);
DISPLAY INVISIBLE (3825 2875);
FORCEPROP 1 LAST HDL_TAP TRUE
J 0
(4150 2700);
DISPLAY 0.872340 (4150 2700);
DISPLAY INVISIBLE (4150 2700);
FORCEPROP 1 LAST PATH I217
J 0
(3823 2825);
DISPLAY 0.872340 (3823 2825);
PAINT GREEN (3823 2825);
DISPLAY INVISIBLE (3823 2825);
FORCEADD TAP..1
(3825 2875);
FORCEPROP 3 LASTPIN (3775 2875) SIG_NAME P5E_CPU0_PE4_TX_DN<11>
J 0
(3785 2885);
DISPLAY 0.659574 (3785 2885);
PAINT MONO (3785 2885);
DISPLAY INVISIBLE (3785 2885);
FORCEPROP 1 LASTPIN (3775 2875) BN 11
J 0
(3763 2883);
DISPLAY 0.680851 (3763 2883);
PAINT GREEN (3763 2883);
FORCEPROP 2 LAST CDS_LIB standard
J 0
(3825 2875);
DISPLAY INVISIBLE (3825 2875);
FORCEPROP 1 LAST BODY_TYPE PLUMBING
J 0
(3825 2925);
DISPLAY 0.872340 (3825 2925);
PAINT GREEN (3825 2925);
DISPLAY INVISIBLE (3825 2925);
FORCEPROP 1 LAST HDL_TAP TRUE
J 0
(4150 2750);
DISPLAY 0.872340 (4150 2750);
DISPLAY INVISIBLE (4150 2750);
FORCEPROP 1 LAST PATH I218
J 0
(3823 2875);
DISPLAY 0.872340 (3823 2875);
PAINT GREEN (3823 2875);
DISPLAY INVISIBLE (3823 2875);
FORCEADD TAP..1
(3825 2925);
FORCEPROP 3 LASTPIN (3775 2925) SIG_NAME P5E_CPU0_PE4_TX_DN<12>
J 0
(3785 2935);
DISPLAY 0.659574 (3785 2935);
PAINT MONO (3785 2935);
DISPLAY INVISIBLE (3785 2935);
FORCEPROP 1 LASTPIN (3775 2925) BN 12
J 0
(3763 2933);
DISPLAY 0.680851 (3763 2933);
PAINT GREEN (3763 2933);
FORCEPROP 2 LAST CDS_LIB standard
J 0
(3825 2925);
DISPLAY INVISIBLE (3825 2925);
FORCEPROP 1 LAST BODY_TYPE PLUMBING
J 0
(3825 2975);
DISPLAY 0.872340 (3825 2975);
PAINT GREEN (3825 2975);
DISPLAY INVISIBLE (3825 2975);
FORCEPROP 1 LAST HDL_TAP TRUE
J 0
(4150 2800);
DISPLAY 0.872340 (4150 2800);
DISPLAY INVISIBLE (4150 2800);
FORCEPROP 1 LAST PATH I219
J 0
(3823 2925);
DISPLAY 0.872340 (3823 2925);
PAINT GREEN (3823 2925);
DISPLAY INVISIBLE (3823 2925);
FORCEADD TAP..1
(3825 2975);
FORCEPROP 3 LASTPIN (3775 2975) SIG_NAME P5E_CPU0_PE4_TX_DN<13>
J 0
(3785 2985);
DISPLAY 0.659574 (3785 2985);
PAINT MONO (3785 2985);
DISPLAY INVISIBLE (3785 2985);
FORCEPROP 1 LASTPIN (3775 2975) BN 13
J 0
(3763 2983);
DISPLAY 0.680851 (3763 2983);
PAINT GREEN (3763 2983);
FORCEPROP 2 LAST CDS_LIB standard
J 0
(3825 2975);
DISPLAY INVISIBLE (3825 2975);
FORCEPROP 1 LAST BODY_TYPE PLUMBING
J 0
(3825 3025);
DISPLAY 0.872340 (3825 3025);
PAINT GREEN (3825 3025);
DISPLAY INVISIBLE (3825 3025);
FORCEPROP 1 LAST HDL_TAP TRUE
J 0
(4150 2850);
DISPLAY 0.872340 (4150 2850);
DISPLAY INVISIBLE (4150 2850);
FORCEPROP 1 LAST PATH I220
J 0
(3823 2975);
DISPLAY 0.872340 (3823 2975);
PAINT GREEN (3823 2975);
DISPLAY INVISIBLE (3823 2975);
FORCEADD TAP..1
(3825 3025);
FORCEPROP 3 LASTPIN (3775 3025) SIG_NAME P5E_CPU0_PE4_TX_DN<14>
J 0
(3785 3035);
DISPLAY 0.659574 (3785 3035);
PAINT MONO (3785 3035);
DISPLAY INVISIBLE (3785 3035);
FORCEPROP 1 LASTPIN (3775 3025) BN 14
J 0
(3763 3033);
DISPLAY 0.680851 (3763 3033);
PAINT GREEN (3763 3033);
FORCEPROP 2 LAST CDS_LIB standard
J 0
(3825 3025);
DISPLAY INVISIBLE (3825 3025);
FORCEPROP 1 LAST BODY_TYPE PLUMBING
J 0
(3825 3075);
DISPLAY 0.872340 (3825 3075);
PAINT GREEN (3825 3075);
DISPLAY INVISIBLE (3825 3075);
FORCEPROP 1 LAST HDL_TAP TRUE
J 0
(4150 2900);
DISPLAY 0.872340 (4150 2900);
DISPLAY INVISIBLE (4150 2900);
FORCEPROP 1 LAST PATH I221
J 0
(3823 3025);
DISPLAY 0.872340 (3823 3025);
PAINT GREEN (3823 3025);
DISPLAY INVISIBLE (3823 3025);
FORCEADD TAP..1
(3825 3075);
FORCEPROP 3 LASTPIN (3775 3075) SIG_NAME P5E_CPU0_PE4_TX_DN<15>
J 0
(3785 3085);
DISPLAY 0.659574 (3785 3085);
PAINT MONO (3785 3085);
DISPLAY INVISIBLE (3785 3085);
FORCEPROP 1 LASTPIN (3775 3075) BN 15
J 0
(3763 3083);
DISPLAY 0.680851 (3763 3083);
PAINT GREEN (3763 3083);
FORCEPROP 2 LAST CDS_LIB standard
J 0
(3825 3075);
DISPLAY INVISIBLE (3825 3075);
FORCEPROP 1 LAST BODY_TYPE PLUMBING
J 0
(3825 3125);
DISPLAY 0.872340 (3825 3125);
PAINT GREEN (3825 3125);
DISPLAY INVISIBLE (3825 3125);
FORCEPROP 1 LAST HDL_TAP TRUE
J 0
(4150 2950);
DISPLAY 0.872340 (4150 2950);
DISPLAY INVISIBLE (4150 2950);
FORCEPROP 1 LAST PATH I222
J 0
(3823 3075);
DISPLAY 0.872340 (3823 3075);
PAINT GREEN (3823 3075);
DISPLAY INVISIBLE (3823 3075);
FORCEADD TAP..1
(3825 3175);
FORCEPROP 3 LASTPIN (3775 3175) SIG_NAME P5E_CPU0_PE4_TX_DP<0>
J 0
(3785 3185);
DISPLAY 0.659574 (3785 3185);
PAINT MONO (3785 3185);
DISPLAY INVISIBLE (3785 3185);
FORCEPROP 1 LASTPIN (3775 3175) BN 0
J 0
(3763 3183);
DISPLAY 0.680851 (3763 3183);
PAINT GREEN (3763 3183);
FORCEPROP 2 LAST CDS_LIB standard
J 0
(3825 3175);
PAINT MONO (3825 3175);
DISPLAY INVISIBLE (3825 3175);
FORCEPROP 1 LAST BODY_TYPE PLUMBING
J 0
(3825 3225);
DISPLAY 0.872340 (3825 3225);
PAINT GREEN (3825 3225);
DISPLAY INVISIBLE (3825 3225);
FORCEPROP 1 LAST HDL_TAP TRUE
J 0
(4150 3050);
DISPLAY 0.872340 (4150 3050);
DISPLAY INVISIBLE (4150 3050);
FORCEPROP 1 LAST PATH I223
J 0
(3823 3175);
DISPLAY 0.872340 (3823 3175);
PAINT GREEN (3823 3175);
DISPLAY INVISIBLE (3823 3175);
FORCEADD TAP..1
(3825 3225);
FORCEPROP 3 LASTPIN (3775 3225) SIG_NAME P5E_CPU0_PE4_TX_DP<1>
J 0
(3785 3235);
DISPLAY 0.659574 (3785 3235);
PAINT MONO (3785 3235);
DISPLAY INVISIBLE (3785 3235);
FORCEPROP 1 LASTPIN (3775 3225) BN 1
J 0
(3763 3233);
DISPLAY 0.680851 (3763 3233);
PAINT GREEN (3763 3233);
FORCEPROP 2 LAST CDS_LIB standard
J 0
(3825 3225);
PAINT MONO (3825 3225);
DISPLAY INVISIBLE (3825 3225);
FORCEPROP 1 LAST BODY_TYPE PLUMBING
J 0
(3825 3275);
DISPLAY 0.872340 (3825 3275);
PAINT GREEN (3825 3275);
DISPLAY INVISIBLE (3825 3275);
FORCEPROP 1 LAST HDL_TAP TRUE
J 0
(4150 3100);
DISPLAY 0.872340 (4150 3100);
DISPLAY INVISIBLE (4150 3100);
FORCEPROP 1 LAST PATH I224
J 0
(3823 3225);
DISPLAY 0.872340 (3823 3225);
PAINT GREEN (3823 3225);
DISPLAY INVISIBLE (3823 3225);
FORCEADD TAP..1
(3825 3275);
FORCEPROP 3 LASTPIN (3775 3275) SIG_NAME P5E_CPU0_PE4_TX_DP<2>
J 0
(3785 3285);
DISPLAY 0.659574 (3785 3285);
PAINT MONO (3785 3285);
DISPLAY INVISIBLE (3785 3285);
FORCEPROP 1 LASTPIN (3775 3275) BN 2
J 0
(3763 3283);
DISPLAY 0.680851 (3763 3283);
PAINT GREEN (3763 3283);
FORCEPROP 2 LAST CDS_LIB standard
J 0
(3825 3275);
PAINT MONO (3825 3275);
DISPLAY INVISIBLE (3825 3275);
FORCEPROP 1 LAST BODY_TYPE PLUMBING
J 0
(3825 3325);
DISPLAY 0.872340 (3825 3325);
PAINT GREEN (3825 3325);
DISPLAY INVISIBLE (3825 3325);
FORCEPROP 1 LAST HDL_TAP TRUE
J 0
(4150 3150);
DISPLAY 0.872340 (4150 3150);
DISPLAY INVISIBLE (4150 3150);
FORCEPROP 1 LAST PATH I225
J 0
(3823 3275);
DISPLAY 0.872340 (3823 3275);
PAINT GREEN (3823 3275);
DISPLAY INVISIBLE (3823 3275);
FORCEADD TAP..1
(3825 3375);
FORCEPROP 3 LASTPIN (3775 3375) SIG_NAME P5E_CPU0_PE4_TX_DP<4>
J 0
(3785 3385);
DISPLAY 0.659574 (3785 3385);
PAINT MONO (3785 3385);
DISPLAY INVISIBLE (3785 3385);
FORCEPROP 1 LASTPIN (3775 3375) BN 4
J 0
(3763 3383);
DISPLAY 0.680851 (3763 3383);
PAINT GREEN (3763 3383);
FORCEPROP 2 LAST CDS_LIB standard
J 0
(3825 3375);
PAINT MONO (3825 3375);
DISPLAY INVISIBLE (3825 3375);
FORCEPROP 1 LAST BODY_TYPE PLUMBING
J 0
(3825 3425);
DISPLAY 0.872340 (3825 3425);
PAINT GREEN (3825 3425);
DISPLAY INVISIBLE (3825 3425);
FORCEPROP 1 LAST HDL_TAP TRUE
J 0
(4150 3250);
DISPLAY 0.872340 (4150 3250);
DISPLAY INVISIBLE (4150 3250);
FORCEPROP 1 LAST PATH I226
J 0
(3823 3375);
DISPLAY 0.872340 (3823 3375);
PAINT GREEN (3823 3375);
DISPLAY INVISIBLE (3823 3375);
FORCEADD TAP..1
(3825 3325);
FORCEPROP 3 LASTPIN (3775 3325) SIG_NAME P5E_CPU0_PE4_TX_DP<3>
J 0
(3785 3335);
DISPLAY 0.659574 (3785 3335);
PAINT MONO (3785 3335);
DISPLAY INVISIBLE (3785 3335);
FORCEPROP 1 LASTPIN (3775 3325) BN 3
J 0
(3763 3333);
DISPLAY 0.680851 (3763 3333);
PAINT GREEN (3763 3333);
FORCEPROP 2 LAST CDS_LIB standard
J 0
(3825 3325);
PAINT MONO (3825 3325);
DISPLAY INVISIBLE (3825 3325);
FORCEPROP 1 LAST BODY_TYPE PLUMBING
J 0
(3825 3375);
DISPLAY 0.872340 (3825 3375);
PAINT GREEN (3825 3375);
DISPLAY INVISIBLE (3825 3375);
FORCEPROP 1 LAST HDL_TAP TRUE
J 0
(4150 3200);
DISPLAY 0.872340 (4150 3200);
DISPLAY INVISIBLE (4150 3200);
FORCEPROP 1 LAST PATH I227
J 0
(3823 3325);
DISPLAY 0.872340 (3823 3325);
PAINT GREEN (3823 3325);
DISPLAY INVISIBLE (3823 3325);
FORCEADD TAP..1
(3825 3425);
FORCEPROP 3 LASTPIN (3775 3425) SIG_NAME P5E_CPU0_PE4_TX_DP<5>
J 0
(3785 3435);
DISPLAY 0.659574 (3785 3435);
PAINT MONO (3785 3435);
DISPLAY INVISIBLE (3785 3435);
FORCEPROP 1 LASTPIN (3775 3425) BN 5
J 0
(3763 3433);
DISPLAY 0.680851 (3763 3433);
PAINT GREEN (3763 3433);
FORCEPROP 2 LAST CDS_LIB standard
J 0
(3825 3425);
PAINT MONO (3825 3425);
DISPLAY INVISIBLE (3825 3425);
FORCEPROP 1 LAST BODY_TYPE PLUMBING
J 0
(3825 3475);
DISPLAY 0.872340 (3825 3475);
PAINT GREEN (3825 3475);
DISPLAY INVISIBLE (3825 3475);
FORCEPROP 1 LAST HDL_TAP TRUE
J 0
(4150 3300);
DISPLAY 0.872340 (4150 3300);
DISPLAY INVISIBLE (4150 3300);
FORCEPROP 1 LAST PATH I228
J 0
(3823 3425);
DISPLAY 0.872340 (3823 3425);
PAINT GREEN (3823 3425);
DISPLAY INVISIBLE (3823 3425);
FORCEADD TAP..1
(3825 3475);
FORCEPROP 3 LASTPIN (3775 3475) SIG_NAME P5E_CPU0_PE4_TX_DP<6>
J 0
(3785 3485);
DISPLAY 0.659574 (3785 3485);
PAINT MONO (3785 3485);
DISPLAY INVISIBLE (3785 3485);
FORCEPROP 1 LASTPIN (3775 3475) BN 6
J 0
(3763 3483);
DISPLAY 0.680851 (3763 3483);
PAINT GREEN (3763 3483);
FORCEPROP 2 LAST CDS_LIB standard
J 0
(3825 3475);
PAINT MONO (3825 3475);
DISPLAY INVISIBLE (3825 3475);
FORCEPROP 1 LAST BODY_TYPE PLUMBING
J 0
(3825 3525);
DISPLAY 0.872340 (3825 3525);
PAINT GREEN (3825 3525);
DISPLAY INVISIBLE (3825 3525);
FORCEPROP 1 LAST HDL_TAP TRUE
J 0
(4150 3350);
DISPLAY 0.872340 (4150 3350);
DISPLAY INVISIBLE (4150 3350);
FORCEPROP 1 LAST PATH I229
J 0
(3823 3475);
DISPLAY 0.872340 (3823 3475);
PAINT GREEN (3823 3475);
DISPLAY INVISIBLE (3823 3475);
FORCEADD TAP..1
(3825 3525);
FORCEPROP 3 LASTPIN (3775 3525) SIG_NAME P5E_CPU0_PE4_TX_DP<7>
J 0
(3785 3535);
DISPLAY 0.659574 (3785 3535);
PAINT MONO (3785 3535);
DISPLAY INVISIBLE (3785 3535);
FORCEPROP 1 LASTPIN (3775 3525) BN 7
J 0
(3763 3533);
DISPLAY 0.680851 (3763 3533);
PAINT GREEN (3763 3533);
FORCEPROP 2 LAST CDS_LIB standard
J 0
(3825 3525);
PAINT MONO (3825 3525);
DISPLAY INVISIBLE (3825 3525);
FORCEPROP 1 LAST BODY_TYPE PLUMBING
J 0
(3825 3575);
DISPLAY 0.872340 (3825 3575);
PAINT GREEN (3825 3575);
DISPLAY INVISIBLE (3825 3575);
FORCEPROP 1 LAST HDL_TAP TRUE
J 0
(4150 3400);
DISPLAY 0.872340 (4150 3400);
DISPLAY INVISIBLE (4150 3400);
FORCEPROP 1 LAST PATH I230
J 0
(3823 3525);
DISPLAY 0.872340 (3823 3525);
PAINT GREEN (3823 3525);
DISPLAY INVISIBLE (3823 3525);
FORCEADD TAP..1
(3825 3625);
FORCEPROP 3 LASTPIN (3775 3625) SIG_NAME P5E_CPU0_PE4_TX_DP<9>
J 0
(3785 3635);
DISPLAY 0.659574 (3785 3635);
PAINT MONO (3785 3635);
DISPLAY INVISIBLE (3785 3635);
FORCEPROP 1 LASTPIN (3775 3625) BN 9
J 0
(3763 3633);
DISPLAY 0.680851 (3763 3633);
PAINT GREEN (3763 3633);
FORCEPROP 2 LAST CDS_LIB standard
J 0
(3825 3625);
DISPLAY INVISIBLE (3825 3625);
FORCEPROP 1 LAST BODY_TYPE PLUMBING
J 0
(3825 3675);
DISPLAY 0.872340 (3825 3675);
PAINT GREEN (3825 3675);
DISPLAY INVISIBLE (3825 3675);
FORCEPROP 1 LAST HDL_TAP TRUE
J 0
(4150 3500);
DISPLAY 0.872340 (4150 3500);
DISPLAY INVISIBLE (4150 3500);
FORCEPROP 1 LAST PATH I231
J 0
(3823 3625);
DISPLAY 0.872340 (3823 3625);
PAINT GREEN (3823 3625);
DISPLAY INVISIBLE (3823 3625);
FORCEADD TAP..1
(3825 3675);
FORCEPROP 3 LASTPIN (3775 3675) SIG_NAME P5E_CPU0_PE4_TX_DP<10>
J 0
(3785 3685);
DISPLAY 0.659574 (3785 3685);
PAINT MONO (3785 3685);
DISPLAY INVISIBLE (3785 3685);
FORCEPROP 1 LASTPIN (3775 3675) BN 10
J 0
(3763 3683);
DISPLAY 0.680851 (3763 3683);
PAINT GREEN (3763 3683);
FORCEPROP 2 LAST CDS_LIB standard
J 0
(3825 3675);
DISPLAY INVISIBLE (3825 3675);
FORCEPROP 1 LAST BODY_TYPE PLUMBING
J 0
(3825 3725);
DISPLAY 0.872340 (3825 3725);
PAINT GREEN (3825 3725);
DISPLAY INVISIBLE (3825 3725);
FORCEPROP 1 LAST HDL_TAP TRUE
J 0
(4150 3550);
DISPLAY 0.872340 (4150 3550);
DISPLAY INVISIBLE (4150 3550);
FORCEPROP 1 LAST PATH I232
J 0
(3823 3675);
DISPLAY 0.872340 (3823 3675);
PAINT GREEN (3823 3675);
DISPLAY INVISIBLE (3823 3675);
FORCEADD TAP..1
(3825 3575);
FORCEPROP 3 LASTPIN (3775 3575) SIG_NAME P5E_CPU0_PE4_TX_DP<8>
J 0
(3785 3585);
DISPLAY 0.659574 (3785 3585);
PAINT MONO (3785 3585);
DISPLAY INVISIBLE (3785 3585);
FORCEPROP 1 LASTPIN (3775 3575) BN 8
J 0
(3763 3583);
DISPLAY 0.680851 (3763 3583);
PAINT GREEN (3763 3583);
FORCEPROP 2 LAST CDS_LIB standard
J 0
(3825 3575);
PAINT MONO (3825 3575);
DISPLAY INVISIBLE (3825 3575);
FORCEPROP 1 LAST BODY_TYPE PLUMBING
J 0
(3825 3625);
DISPLAY 0.872340 (3825 3625);
PAINT GREEN (3825 3625);
DISPLAY INVISIBLE (3825 3625);
FORCEPROP 1 LAST HDL_TAP TRUE
J 0
(4150 3450);
DISPLAY 0.872340 (4150 3450);
DISPLAY INVISIBLE (4150 3450);
FORCEPROP 1 LAST PATH I233
J 0
(3823 3575);
DISPLAY 0.872340 (3823 3575);
PAINT GREEN (3823 3575);
DISPLAY INVISIBLE (3823 3575);
FORCEADD TAP..1
(3825 3825);
FORCEPROP 3 LASTPIN (3775 3825) SIG_NAME P5E_CPU0_PE4_TX_DP<13>
J 0
(3785 3835);
DISPLAY 0.659574 (3785 3835);
PAINT MONO (3785 3835);
DISPLAY INVISIBLE (3785 3835);
FORCEPROP 1 LASTPIN (3775 3825) BN 13
J 0
(3763 3833);
DISPLAY 0.680851 (3763 3833);
PAINT GREEN (3763 3833);
FORCEPROP 2 LAST CDS_LIB standard
J 0
(3825 3825);
DISPLAY INVISIBLE (3825 3825);
FORCEPROP 1 LAST BODY_TYPE PLUMBING
J 0
(3825 3875);
DISPLAY 0.872340 (3825 3875);
PAINT GREEN (3825 3875);
DISPLAY INVISIBLE (3825 3875);
FORCEPROP 1 LAST HDL_TAP TRUE
J 0
(4150 3700);
DISPLAY 0.872340 (4150 3700);
DISPLAY INVISIBLE (4150 3700);
FORCEPROP 1 LAST PATH I234
J 0
(3823 3825);
DISPLAY 0.872340 (3823 3825);
PAINT GREEN (3823 3825);
DISPLAY INVISIBLE (3823 3825);
FORCEADD TAP..1
(3825 3925);
FORCEPROP 3 LASTPIN (3775 3925) SIG_NAME P5E_CPU0_PE4_TX_DP<15>
J 0
(3785 3935);
DISPLAY 0.659574 (3785 3935);
PAINT MONO (3785 3935);
DISPLAY INVISIBLE (3785 3935);
FORCEPROP 1 LASTPIN (3775 3925) BN 15
J 0
(3763 3933);
DISPLAY 0.680851 (3763 3933);
PAINT GREEN (3763 3933);
FORCEPROP 2 LAST CDS_LIB standard
J 0
(3825 3925);
DISPLAY INVISIBLE (3825 3925);
FORCEPROP 1 LAST BODY_TYPE PLUMBING
J 0
(3825 3975);
DISPLAY 0.872340 (3825 3975);
PAINT GREEN (3825 3975);
DISPLAY INVISIBLE (3825 3975);
FORCEPROP 1 LAST HDL_TAP TRUE
J 0
(4150 3800);
DISPLAY 0.872340 (4150 3800);
DISPLAY INVISIBLE (4150 3800);
FORCEPROP 1 LAST PATH I235
J 0
(3823 3925);
DISPLAY 0.872340 (3823 3925);
PAINT GREEN (3823 3925);
DISPLAY INVISIBLE (3823 3925);
FORCEADD TAP..1
(3825 3875);
FORCEPROP 3 LASTPIN (3775 3875) SIG_NAME P5E_CPU0_PE4_TX_DP<14>
J 0
(3785 3885);
DISPLAY 0.659574 (3785 3885);
PAINT MONO (3785 3885);
DISPLAY INVISIBLE (3785 3885);
FORCEPROP 1 LASTPIN (3775 3875) BN 14
J 0
(3763 3883);
DISPLAY 0.680851 (3763 3883);
PAINT GREEN (3763 3883);
FORCEPROP 2 LAST CDS_LIB standard
J 0
(3825 3875);
DISPLAY INVISIBLE (3825 3875);
FORCEPROP 1 LAST BODY_TYPE PLUMBING
J 0
(3825 3925);
DISPLAY 0.872340 (3825 3925);
PAINT GREEN (3825 3925);
DISPLAY INVISIBLE (3825 3925);
FORCEPROP 1 LAST HDL_TAP TRUE
J 0
(4150 3750);
DISPLAY 0.872340 (4150 3750);
DISPLAY INVISIBLE (4150 3750);
FORCEPROP 1 LAST PATH I236
J 0
(3823 3875);
DISPLAY 0.872340 (3823 3875);
PAINT GREEN (3823 3875);
DISPLAY INVISIBLE (3823 3875);
FORCEADD TAP..1
(3825 3725);
FORCEPROP 3 LASTPIN (3775 3725) SIG_NAME P5E_CPU0_PE4_TX_DP<11>
J 0
(3785 3735);
DISPLAY 0.659574 (3785 3735);
PAINT MONO (3785 3735);
DISPLAY INVISIBLE (3785 3735);
FORCEPROP 1 LASTPIN (3775 3725) BN 11
J 0
(3763 3733);
DISPLAY 0.680851 (3763 3733);
PAINT GREEN (3763 3733);
FORCEPROP 2 LAST CDS_LIB standard
J 0
(3825 3725);
DISPLAY INVISIBLE (3825 3725);
FORCEPROP 1 LAST BODY_TYPE PLUMBING
J 0
(3825 3775);
DISPLAY 0.872340 (3825 3775);
PAINT GREEN (3825 3775);
DISPLAY INVISIBLE (3825 3775);
FORCEPROP 1 LAST HDL_TAP TRUE
J 0
(4150 3600);
DISPLAY 0.872340 (4150 3600);
DISPLAY INVISIBLE (4150 3600);
FORCEPROP 1 LAST PATH I237
J 0
(3823 3725);
DISPLAY 0.872340 (3823 3725);
PAINT GREEN (3823 3725);
DISPLAY INVISIBLE (3823 3725);
FORCEADD TAP..1
(3825 3775);
FORCEPROP 3 LASTPIN (3775 3775) SIG_NAME P5E_CPU0_PE4_TX_DP<12>
J 0
(3785 3785);
DISPLAY 0.659574 (3785 3785);
PAINT MONO (3785 3785);
DISPLAY INVISIBLE (3785 3785);
FORCEPROP 1 LASTPIN (3775 3775) BN 12
J 0
(3763 3783);
DISPLAY 0.680851 (3763 3783);
PAINT GREEN (3763 3783);
FORCEPROP 2 LAST CDS_LIB standard
J 0
(3825 3775);
DISPLAY INVISIBLE (3825 3775);
FORCEPROP 1 LAST BODY_TYPE PLUMBING
J 0
(3825 3825);
DISPLAY 0.872340 (3825 3825);
PAINT GREEN (3825 3825);
DISPLAY INVISIBLE (3825 3825);
FORCEPROP 1 LAST HDL_TAP TRUE
J 0
(4150 3650);
DISPLAY 0.872340 (4150 3650);
DISPLAY INVISIBLE (4150 3650);
FORCEPROP 1 LAST PATH I238
J 0
(3823 3775);
DISPLAY 0.872340 (3823 3775);
PAINT GREEN (3823 3775);
DISPLAY INVISIBLE (3823 3775);
FORCEADD OFFPAGE..2
(4925 3100);
FORCEPROP 2 LAST $XR0 175 
J 0
(5114 3100);
DISPLAY 0.638298 (5114 3100);
PAINT MONO (5114 3100);
FORCEPROP 2 LAST CDS_LIB standard
J 0
(4925 3100);
PAINT MONO (4925 3100);
DISPLAY INVISIBLE (4925 3100);
FORCEPROP 1 LAST OFFPAGE TRUE
J 0
(5250 2975);
DISPLAY 1.170213 (5250 2975);
PAINT GREEN (5250 2975);
DISPLAY INVISIBLE (5250 2975);
FORCEPROP 1 LAST COMMENT_BODY TRUE
J 0
(4880 3005);
DISPLAY 1.170213 (4880 3005);
PAINT GREEN (4880 3005);
DISPLAY INVISIBLE (4880 3005);
FORCEPROP 2 LAST PATH I239
J 0
(5125 3150);
DISPLAY 1.021277 (5125 3150);
DISPLAY INVISIBLE (5125 3150);
FORCEADD OFFPAGE..2
(4925 3950);
FORCEPROP 2 LAST $XR0 175 
J 0
(5114 3950);
DISPLAY 0.638298 (5114 3950);
PAINT MONO (5114 3950);
FORCEPROP 2 LAST CDS_LIB standard
J 0
(4925 3950);
PAINT MONO (4925 3950);
DISPLAY INVISIBLE (4925 3950);
FORCEPROP 1 LAST OFFPAGE TRUE
J 0
(5250 3825);
DISPLAY 1.170213 (5250 3825);
PAINT GREEN (5250 3825);
DISPLAY INVISIBLE (5250 3825);
FORCEPROP 1 LAST COMMENT_BODY TRUE
J 0
(4880 3855);
DISPLAY 1.170213 (4880 3855);
PAINT GREEN (4880 3855);
DISPLAY INVISIBLE (4880 3855);
FORCEPROP 2 LAST PATH I240
J 0
(5125 4000);
DISPLAY 1.021277 (5125 4000);
DISPLAY INVISIBLE (5125 4000);
FORCEADD OFFPAGE..1
(-850 3100);
FORCEPROP 2 LAST $XR1 139 
J 0
(-1222 3100);
DISPLAY 0.638298 (-1222 3100);
PAINT MONO (-1222 3100);
FORCEPROP 2 LAST $XR0 138 
J 0
(-1102 3100);
DISPLAY 0.638298 (-1102 3100);
PAINT MONO (-1102 3100);
FORCEPROP 2 LAST CDS_LIB standard
J 0
(-850 3100);
DISPLAY INVISIBLE (-850 3100);
FORCEPROP 1 LAST OFFPAGE TRUE
J 0
(-525 2975);
DISPLAY 0.872340 (-525 2975);
DISPLAY INVISIBLE (-525 2975);
FORCEPROP 1 LAST COMMENT_BODY TRUE
J 0
(-725 3000);
DISPLAY 0.872340 (-725 3000);
PAINT GREEN (-725 3000);
DISPLAY INVISIBLE (-725 3000);
FORCEPROP 2 LAST PATH I241
J 0
(-1100 3150);
DISPLAY 1.021277 (-1100 3150);
DISPLAY INVISIBLE (-1100 3150);
FORCEADD OFFPAGE..1
(-850 3950);
FORCEPROP 2 LAST $XR1 139 
J 0
(-1222 3950);
DISPLAY 0.638298 (-1222 3950);
PAINT MONO (-1222 3950);
FORCEPROP 2 LAST $XR0 138 
J 0
(-1102 3950);
DISPLAY 0.638298 (-1102 3950);
PAINT MONO (-1102 3950);
FORCEPROP 2 LAST CDS_LIB standard
J 0
(-850 3950);
DISPLAY INVISIBLE (-850 3950);
FORCEPROP 1 LAST OFFPAGE TRUE
J 0
(-525 3825);
DISPLAY 0.872340 (-525 3825);
DISPLAY INVISIBLE (-525 3825);
FORCEPROP 1 LAST COMMENT_BODY TRUE
J 0
(-725 3850);
DISPLAY 0.872340 (-725 3850);
PAINT GREEN (-725 3850);
DISPLAY INVISIBLE (-725 3850);
FORCEPROP 2 LAST PATH I242
J 0
(-1100 4000);
DISPLAY 1.021277 (-1100 4000);
DISPLAY INVISIBLE (-1100 4000);
FORCEADD TAP..1
R 2
(400 2325);
FORCEPROP 3 LASTPIN (450 2325) SIG_NAME P5E_CPU0_PE4_RX_DN<0>
J 0
(460 2335);
DISPLAY 0.659574 (460 2335);
PAINT MONO (460 2335);
DISPLAY INVISIBLE (460 2335);
FORCEPROP 1 LASTPIN (450 2325) BN 0
J 2
(462 2333);
DISPLAY 0.680851 (462 2333);
PAINT GREEN (462 2333);
FORCEPROP 2 LAST CDS_LIB standard
J 0
(400 2325);
DISPLAY INVISIBLE (400 2325);
FORCEPROP 1 LAST BODY_TYPE PLUMBING
J 2
(400 2375);
DISPLAY 0.872340 (400 2375);
PAINT GREEN (400 2375);
DISPLAY INVISIBLE (400 2375);
FORCEPROP 1 LAST HDL_TAP TRUE
J 2
(75 2200);
DISPLAY 0.872340 (75 2200);
DISPLAY INVISIBLE (75 2200);
FORCEPROP 1 LAST PATH I243
J 2
(402 2325);
DISPLAY 0.872340 (402 2325);
PAINT GREEN (402 2325);
DISPLAY INVISIBLE (402 2325);
FORCEADD TAP..1
R 2
(400 2375);
FORCEPROP 3 LASTPIN (450 2375) SIG_NAME P5E_CPU0_PE4_RX_DN<1>
J 0
(460 2385);
DISPLAY 0.659574 (460 2385);
PAINT MONO (460 2385);
DISPLAY INVISIBLE (460 2385);
FORCEPROP 1 LASTPIN (450 2375) BN 1
J 2
(462 2383);
DISPLAY 0.680851 (462 2383);
PAINT GREEN (462 2383);
FORCEPROP 2 LAST CDS_LIB standard
J 0
(400 2375);
DISPLAY INVISIBLE (400 2375);
FORCEPROP 1 LAST BODY_TYPE PLUMBING
J 2
(400 2425);
DISPLAY 0.872340 (400 2425);
PAINT GREEN (400 2425);
DISPLAY INVISIBLE (400 2425);
FORCEPROP 1 LAST HDL_TAP TRUE
J 2
(75 2250);
DISPLAY 0.872340 (75 2250);
DISPLAY INVISIBLE (75 2250);
FORCEPROP 1 LAST PATH I244
J 2
(402 2375);
DISPLAY 0.872340 (402 2375);
PAINT GREEN (402 2375);
DISPLAY INVISIBLE (402 2375);
FORCEADD TAP..1
R 2
(400 2425);
FORCEPROP 3 LASTPIN (450 2425) SIG_NAME P5E_CPU0_PE4_RX_DN<2>
J 0
(460 2435);
DISPLAY 0.659574 (460 2435);
PAINT MONO (460 2435);
DISPLAY INVISIBLE (460 2435);
FORCEPROP 1 LASTPIN (450 2425) BN 2
J 2
(462 2433);
DISPLAY 0.680851 (462 2433);
PAINT GREEN (462 2433);
FORCEPROP 2 LAST CDS_LIB standard
J 0
(400 2425);
DISPLAY INVISIBLE (400 2425);
FORCEPROP 1 LAST BODY_TYPE PLUMBING
J 2
(400 2475);
DISPLAY 0.872340 (400 2475);
PAINT GREEN (400 2475);
DISPLAY INVISIBLE (400 2475);
FORCEPROP 1 LAST HDL_TAP TRUE
J 2
(75 2300);
DISPLAY 0.872340 (75 2300);
DISPLAY INVISIBLE (75 2300);
FORCEPROP 1 LAST PATH I245
J 2
(402 2425);
DISPLAY 0.872340 (402 2425);
PAINT GREEN (402 2425);
DISPLAY INVISIBLE (402 2425);
FORCEADD TAP..1
R 2
(400 2575);
FORCEPROP 3 LASTPIN (450 2575) SIG_NAME P5E_CPU0_PE4_RX_DN<5>
J 0
(460 2585);
DISPLAY 0.659574 (460 2585);
PAINT MONO (460 2585);
DISPLAY INVISIBLE (460 2585);
FORCEPROP 1 LASTPIN (450 2575) BN 5
J 2
(462 2583);
DISPLAY 0.680851 (462 2583);
PAINT GREEN (462 2583);
FORCEPROP 2 LAST CDS_LIB standard
J 0
(400 2575);
DISPLAY INVISIBLE (400 2575);
FORCEPROP 1 LAST BODY_TYPE PLUMBING
J 2
(400 2625);
DISPLAY 0.872340 (400 2625);
PAINT GREEN (400 2625);
DISPLAY INVISIBLE (400 2625);
FORCEPROP 1 LAST HDL_TAP TRUE
J 2
(75 2450);
DISPLAY 0.872340 (75 2450);
DISPLAY INVISIBLE (75 2450);
FORCEPROP 1 LAST PATH I246
J 2
(402 2575);
DISPLAY 0.872340 (402 2575);
PAINT GREEN (402 2575);
DISPLAY INVISIBLE (402 2575);
FORCEADD TAP..1
R 2
(400 2525);
FORCEPROP 3 LASTPIN (450 2525) SIG_NAME P5E_CPU0_PE4_RX_DN<4>
J 0
(460 2535);
DISPLAY 0.659574 (460 2535);
PAINT MONO (460 2535);
DISPLAY INVISIBLE (460 2535);
FORCEPROP 1 LASTPIN (450 2525) BN 4
J 2
(462 2533);
DISPLAY 0.680851 (462 2533);
PAINT GREEN (462 2533);
FORCEPROP 2 LAST CDS_LIB standard
J 0
(400 2525);
DISPLAY INVISIBLE (400 2525);
FORCEPROP 1 LAST BODY_TYPE PLUMBING
J 2
(400 2575);
DISPLAY 0.872340 (400 2575);
PAINT GREEN (400 2575);
DISPLAY INVISIBLE (400 2575);
FORCEPROP 1 LAST HDL_TAP TRUE
J 2
(75 2400);
DISPLAY 0.872340 (75 2400);
DISPLAY INVISIBLE (75 2400);
FORCEPROP 1 LAST PATH I247
J 2
(402 2525);
DISPLAY 0.872340 (402 2525);
PAINT GREEN (402 2525);
DISPLAY INVISIBLE (402 2525);
FORCEADD TAP..1
R 2
(400 2625);
FORCEPROP 3 LASTPIN (450 2625) SIG_NAME P5E_CPU0_PE4_RX_DN<6>
J 0
(460 2635);
DISPLAY 0.659574 (460 2635);
PAINT MONO (460 2635);
DISPLAY INVISIBLE (460 2635);
FORCEPROP 1 LASTPIN (450 2625) BN 6
J 2
(462 2633);
DISPLAY 0.680851 (462 2633);
PAINT GREEN (462 2633);
FORCEPROP 2 LAST CDS_LIB standard
J 0
(400 2625);
DISPLAY INVISIBLE (400 2625);
FORCEPROP 1 LAST BODY_TYPE PLUMBING
J 2
(400 2675);
DISPLAY 0.872340 (400 2675);
PAINT GREEN (400 2675);
DISPLAY INVISIBLE (400 2675);
FORCEPROP 1 LAST HDL_TAP TRUE
J 2
(75 2500);
DISPLAY 0.872340 (75 2500);
DISPLAY INVISIBLE (75 2500);
FORCEPROP 1 LAST PATH I248
J 2
(402 2625);
DISPLAY 0.872340 (402 2625);
PAINT GREEN (402 2625);
DISPLAY INVISIBLE (402 2625);
FORCEADD TAP..1
R 2
(400 2675);
FORCEPROP 3 LASTPIN (450 2675) SIG_NAME P5E_CPU0_PE4_RX_DN<7>
J 0
(460 2685);
DISPLAY 0.659574 (460 2685);
PAINT MONO (460 2685);
DISPLAY INVISIBLE (460 2685);
FORCEPROP 1 LASTPIN (450 2675) BN 7
J 2
(462 2683);
DISPLAY 0.680851 (462 2683);
PAINT GREEN (462 2683);
FORCEPROP 2 LAST CDS_LIB standard
J 0
(400 2675);
DISPLAY INVISIBLE (400 2675);
FORCEPROP 1 LAST BODY_TYPE PLUMBING
J 2
(400 2725);
DISPLAY 0.872340 (400 2725);
PAINT GREEN (400 2725);
DISPLAY INVISIBLE (400 2725);
FORCEPROP 1 LAST HDL_TAP TRUE
J 2
(75 2550);
DISPLAY 0.872340 (75 2550);
DISPLAY INVISIBLE (75 2550);
FORCEPROP 1 LAST PATH I249
J 2
(402 2675);
DISPLAY 0.872340 (402 2675);
PAINT GREEN (402 2675);
DISPLAY INVISIBLE (402 2675);
FORCEADD TAP..1
R 2
(400 2725);
FORCEPROP 3 LASTPIN (450 2725) SIG_NAME P5E_CPU0_PE4_RX_DN<8>
J 0
(460 2735);
DISPLAY 0.659574 (460 2735);
PAINT MONO (460 2735);
DISPLAY INVISIBLE (460 2735);
FORCEPROP 1 LASTPIN (450 2725) BN 8
J 2
(462 2733);
DISPLAY 0.680851 (462 2733);
PAINT GREEN (462 2733);
FORCEPROP 2 LAST CDS_LIB standard
J 0
(400 2725);
DISPLAY INVISIBLE (400 2725);
FORCEPROP 1 LAST BODY_TYPE PLUMBING
J 2
(400 2775);
DISPLAY 0.872340 (400 2775);
PAINT GREEN (400 2775);
DISPLAY INVISIBLE (400 2775);
FORCEPROP 1 LAST HDL_TAP TRUE
J 2
(75 2600);
DISPLAY 0.872340 (75 2600);
DISPLAY INVISIBLE (75 2600);
FORCEPROP 1 LAST PATH I250
J 2
(402 2725);
DISPLAY 0.872340 (402 2725);
PAINT GREEN (402 2725);
DISPLAY INVISIBLE (402 2725);
FORCEADD TAP..1
R 2
(400 2825);
FORCEPROP 3 LASTPIN (450 2825) SIG_NAME P5E_CPU0_PE4_RX_DN<10>
J 0
(460 2835);
DISPLAY 0.659574 (460 2835);
PAINT MONO (460 2835);
DISPLAY INVISIBLE (460 2835);
FORCEPROP 1 LASTPIN (450 2825) BN 10
J 2
(462 2833);
DISPLAY 0.680851 (462 2833);
PAINT GREEN (462 2833);
FORCEPROP 2 LAST CDS_LIB standard
J 0
(400 2825);
DISPLAY INVISIBLE (400 2825);
FORCEPROP 1 LAST BODY_TYPE PLUMBING
J 2
(400 2875);
DISPLAY 0.872340 (400 2875);
PAINT GREEN (400 2875);
DISPLAY INVISIBLE (400 2875);
FORCEPROP 1 LAST HDL_TAP TRUE
J 2
(75 2700);
DISPLAY 0.872340 (75 2700);
DISPLAY INVISIBLE (75 2700);
FORCEPROP 1 LAST PATH I251
J 2
(402 2825);
DISPLAY 0.872340 (402 2825);
PAINT GREEN (402 2825);
DISPLAY INVISIBLE (402 2825);
FORCEADD TAP..1
R 2
(400 2875);
FORCEPROP 3 LASTPIN (450 2875) SIG_NAME P5E_CPU0_PE4_RX_DN<11>
J 0
(460 2885);
DISPLAY 0.659574 (460 2885);
PAINT MONO (460 2885);
DISPLAY INVISIBLE (460 2885);
FORCEPROP 1 LASTPIN (450 2875) BN 11
J 2
(462 2883);
DISPLAY 0.680851 (462 2883);
PAINT GREEN (462 2883);
FORCEPROP 2 LAST CDS_LIB standard
J 0
(400 2875);
DISPLAY INVISIBLE (400 2875);
FORCEPROP 1 LAST BODY_TYPE PLUMBING
J 2
(400 2925);
DISPLAY 0.872340 (400 2925);
PAINT GREEN (400 2925);
DISPLAY INVISIBLE (400 2925);
FORCEPROP 1 LAST HDL_TAP TRUE
J 2
(75 2750);
DISPLAY 0.872340 (75 2750);
DISPLAY INVISIBLE (75 2750);
FORCEPROP 1 LAST PATH I252
J 2
(402 2875);
DISPLAY 0.872340 (402 2875);
PAINT GREEN (402 2875);
DISPLAY INVISIBLE (402 2875);
FORCEADD TAP..1
R 2
(400 2775);
FORCEPROP 3 LASTPIN (450 2775) SIG_NAME P5E_CPU0_PE4_RX_DN<9>
J 0
(460 2785);
DISPLAY 0.659574 (460 2785);
PAINT MONO (460 2785);
DISPLAY INVISIBLE (460 2785);
FORCEPROP 1 LASTPIN (450 2775) BN 9
J 2
(462 2783);
DISPLAY 0.680851 (462 2783);
PAINT GREEN (462 2783);
FORCEPROP 2 LAST CDS_LIB standard
J 0
(400 2775);
DISPLAY INVISIBLE (400 2775);
FORCEPROP 1 LAST BODY_TYPE PLUMBING
J 2
(400 2825);
DISPLAY 0.872340 (400 2825);
PAINT GREEN (400 2825);
DISPLAY INVISIBLE (400 2825);
FORCEPROP 1 LAST HDL_TAP TRUE
J 2
(75 2650);
DISPLAY 0.872340 (75 2650);
DISPLAY INVISIBLE (75 2650);
FORCEPROP 1 LAST PATH I253
J 2
(402 2775);
DISPLAY 0.872340 (402 2775);
PAINT GREEN (402 2775);
DISPLAY INVISIBLE (402 2775);
FORCEADD TAP..1
R 2
(400 3025);
FORCEPROP 3 LASTPIN (450 3025) SIG_NAME P5E_CPU0_PE4_RX_DN<14>
J 0
(460 3035);
DISPLAY 0.659574 (460 3035);
PAINT MONO (460 3035);
DISPLAY INVISIBLE (460 3035);
FORCEPROP 1 LASTPIN (450 3025) BN 14
J 2
(462 3033);
DISPLAY 0.680851 (462 3033);
PAINT GREEN (462 3033);
FORCEPROP 2 LAST CDS_LIB standard
J 0
(400 3025);
DISPLAY INVISIBLE (400 3025);
FORCEPROP 1 LAST BODY_TYPE PLUMBING
J 2
(400 3075);
DISPLAY 0.872340 (400 3075);
PAINT GREEN (400 3075);
DISPLAY INVISIBLE (400 3075);
FORCEPROP 1 LAST HDL_TAP TRUE
J 2
(75 2900);
DISPLAY 0.872340 (75 2900);
DISPLAY INVISIBLE (75 2900);
FORCEPROP 1 LAST PATH I254
J 2
(402 3025);
DISPLAY 0.872340 (402 3025);
PAINT GREEN (402 3025);
DISPLAY INVISIBLE (402 3025);
FORCEADD TAP..1
R 2
(400 3075);
FORCEPROP 3 LASTPIN (450 3075) SIG_NAME P5E_CPU0_PE4_RX_DN<15>
J 0
(460 3085);
DISPLAY 0.659574 (460 3085);
PAINT MONO (460 3085);
DISPLAY INVISIBLE (460 3085);
FORCEPROP 1 LASTPIN (450 3075) BN 15
J 2
(462 3083);
DISPLAY 0.680851 (462 3083);
PAINT GREEN (462 3083);
FORCEPROP 2 LAST CDS_LIB standard
J 0
(400 3075);
DISPLAY INVISIBLE (400 3075);
FORCEPROP 1 LAST BODY_TYPE PLUMBING
J 2
(400 3125);
DISPLAY 0.872340 (400 3125);
PAINT GREEN (400 3125);
DISPLAY INVISIBLE (400 3125);
FORCEPROP 1 LAST HDL_TAP TRUE
J 2
(75 2950);
DISPLAY 0.872340 (75 2950);
DISPLAY INVISIBLE (75 2950);
FORCEPROP 1 LAST PATH I255
J 2
(402 3075);
DISPLAY 0.872340 (402 3075);
PAINT GREEN (402 3075);
DISPLAY INVISIBLE (402 3075);
FORCEADD TAP..1
R 2
(400 2975);
FORCEPROP 3 LASTPIN (450 2975) SIG_NAME P5E_CPU0_PE4_RX_DN<13>
J 0
(460 2985);
DISPLAY 0.659574 (460 2985);
PAINT MONO (460 2985);
DISPLAY INVISIBLE (460 2985);
FORCEPROP 1 LASTPIN (450 2975) BN 13
J 2
(462 2983);
DISPLAY 0.680851 (462 2983);
PAINT GREEN (462 2983);
FORCEPROP 2 LAST CDS_LIB standard
J 0
(400 2975);
DISPLAY INVISIBLE (400 2975);
FORCEPROP 1 LAST BODY_TYPE PLUMBING
J 2
(400 3025);
DISPLAY 0.872340 (400 3025);
PAINT GREEN (400 3025);
DISPLAY INVISIBLE (400 3025);
FORCEPROP 1 LAST HDL_TAP TRUE
J 2
(75 2850);
DISPLAY 0.872340 (75 2850);
DISPLAY INVISIBLE (75 2850);
FORCEPROP 1 LAST PATH I256
J 2
(402 2975);
DISPLAY 0.872340 (402 2975);
PAINT GREEN (402 2975);
DISPLAY INVISIBLE (402 2975);
FORCEADD TAP..1
R 2
(400 2925);
FORCEPROP 3 LASTPIN (450 2925) SIG_NAME P5E_CPU0_PE4_RX_DN<12>
J 0
(460 2935);
DISPLAY 0.659574 (460 2935);
PAINT MONO (460 2935);
DISPLAY INVISIBLE (460 2935);
FORCEPROP 1 LASTPIN (450 2925) BN 12
J 2
(462 2933);
DISPLAY 0.680851 (462 2933);
PAINT GREEN (462 2933);
FORCEPROP 2 LAST CDS_LIB standard
J 0
(400 2925);
DISPLAY INVISIBLE (400 2925);
FORCEPROP 1 LAST BODY_TYPE PLUMBING
J 2
(400 2975);
DISPLAY 0.872340 (400 2975);
PAINT GREEN (400 2975);
DISPLAY INVISIBLE (400 2975);
FORCEPROP 1 LAST HDL_TAP TRUE
J 2
(75 2800);
DISPLAY 0.872340 (75 2800);
DISPLAY INVISIBLE (75 2800);
FORCEPROP 1 LAST PATH I257
J 2
(402 2925);
DISPLAY 0.872340 (402 2925);
PAINT GREEN (402 2925);
DISPLAY INVISIBLE (402 2925);
FORCEADD TAP..1
R 2
(400 3175);
FORCEPROP 3 LASTPIN (450 3175) SIG_NAME P5E_CPU0_PE4_RX_DP<0>
J 0
(460 3185);
DISPLAY 0.659574 (460 3185);
PAINT MONO (460 3185);
DISPLAY INVISIBLE (460 3185);
FORCEPROP 1 LASTPIN (450 3175) BN 0
J 2
(462 3183);
DISPLAY 0.680851 (462 3183);
PAINT GREEN (462 3183);
FORCEPROP 2 LAST CDS_LIB standard
J 0
(400 3175);
DISPLAY INVISIBLE (400 3175);
FORCEPROP 1 LAST BODY_TYPE PLUMBING
J 2
(400 3225);
DISPLAY 0.872340 (400 3225);
PAINT GREEN (400 3225);
DISPLAY INVISIBLE (400 3225);
FORCEPROP 1 LAST HDL_TAP TRUE
J 2
(75 3050);
DISPLAY 0.872340 (75 3050);
DISPLAY INVISIBLE (75 3050);
FORCEPROP 1 LAST PATH I258
J 2
(402 3175);
DISPLAY 0.872340 (402 3175);
PAINT GREEN (402 3175);
DISPLAY INVISIBLE (402 3175);
FORCEADD TAP..1
R 2
(400 3225);
FORCEPROP 3 LASTPIN (450 3225) SIG_NAME P5E_CPU0_PE4_RX_DP<1>
J 0
(460 3235);
DISPLAY 0.659574 (460 3235);
PAINT MONO (460 3235);
DISPLAY INVISIBLE (460 3235);
FORCEPROP 1 LASTPIN (450 3225) BN 1
J 2
(462 3233);
DISPLAY 0.680851 (462 3233);
PAINT GREEN (462 3233);
FORCEPROP 2 LAST CDS_LIB standard
J 0
(400 3225);
DISPLAY INVISIBLE (400 3225);
FORCEPROP 1 LAST BODY_TYPE PLUMBING
J 2
(400 3275);
DISPLAY 0.872340 (400 3275);
PAINT GREEN (400 3275);
DISPLAY INVISIBLE (400 3275);
FORCEPROP 1 LAST HDL_TAP TRUE
J 2
(75 3100);
DISPLAY 0.872340 (75 3100);
DISPLAY INVISIBLE (75 3100);
FORCEPROP 1 LAST PATH I259
J 2
(402 3225);
DISPLAY 0.872340 (402 3225);
PAINT GREEN (402 3225);
DISPLAY INVISIBLE (402 3225);
FORCEADD TAP..1
R 2
(400 3275);
FORCEPROP 3 LASTPIN (450 3275) SIG_NAME P5E_CPU0_PE4_RX_DP<2>
J 0
(460 3285);
DISPLAY 0.659574 (460 3285);
PAINT MONO (460 3285);
DISPLAY INVISIBLE (460 3285);
FORCEPROP 1 LASTPIN (450 3275) BN 2
J 2
(462 3283);
DISPLAY 0.680851 (462 3283);
PAINT GREEN (462 3283);
FORCEPROP 2 LAST CDS_LIB standard
J 0
(400 3275);
DISPLAY INVISIBLE (400 3275);
FORCEPROP 1 LAST BODY_TYPE PLUMBING
J 2
(400 3325);
DISPLAY 0.872340 (400 3325);
PAINT GREEN (400 3325);
DISPLAY INVISIBLE (400 3325);
FORCEPROP 1 LAST HDL_TAP TRUE
J 2
(75 3150);
DISPLAY 0.872340 (75 3150);
DISPLAY INVISIBLE (75 3150);
FORCEPROP 1 LAST PATH I260
J 2
(402 3275);
DISPLAY 0.872340 (402 3275);
PAINT GREEN (402 3275);
DISPLAY INVISIBLE (402 3275);
FORCEADD TAP..1
R 2
(400 3375);
FORCEPROP 3 LASTPIN (450 3375) SIG_NAME P5E_CPU0_PE4_RX_DP<4>
J 0
(460 3385);
DISPLAY 0.659574 (460 3385);
PAINT MONO (460 3385);
DISPLAY INVISIBLE (460 3385);
FORCEPROP 1 LASTPIN (450 3375) BN 4
J 2
(462 3383);
DISPLAY 0.680851 (462 3383);
PAINT GREEN (462 3383);
FORCEPROP 2 LAST CDS_LIB standard
J 0
(400 3375);
DISPLAY INVISIBLE (400 3375);
FORCEPROP 1 LAST BODY_TYPE PLUMBING
J 2
(400 3425);
DISPLAY 0.872340 (400 3425);
PAINT GREEN (400 3425);
DISPLAY INVISIBLE (400 3425);
FORCEPROP 1 LAST HDL_TAP TRUE
J 2
(75 3250);
DISPLAY 0.872340 (75 3250);
DISPLAY INVISIBLE (75 3250);
FORCEPROP 1 LAST PATH I261
J 2
(402 3375);
DISPLAY 0.872340 (402 3375);
PAINT GREEN (402 3375);
DISPLAY INVISIBLE (402 3375);
FORCEADD TAP..1
R 2
(400 3325);
FORCEPROP 3 LASTPIN (450 3325) SIG_NAME P5E_CPU0_PE4_RX_DP<3>
J 0
(460 3335);
DISPLAY 0.659574 (460 3335);
PAINT MONO (460 3335);
DISPLAY INVISIBLE (460 3335);
FORCEPROP 1 LASTPIN (450 3325) BN 3
J 2
(462 3333);
DISPLAY 0.680851 (462 3333);
PAINT GREEN (462 3333);
FORCEPROP 2 LAST CDS_LIB standard
J 0
(400 3325);
DISPLAY INVISIBLE (400 3325);
FORCEPROP 1 LAST BODY_TYPE PLUMBING
J 2
(400 3375);
DISPLAY 0.872340 (400 3375);
PAINT GREEN (400 3375);
DISPLAY INVISIBLE (400 3375);
FORCEPROP 1 LAST HDL_TAP TRUE
J 2
(75 3200);
DISPLAY 0.872340 (75 3200);
DISPLAY INVISIBLE (75 3200);
FORCEPROP 1 LAST PATH I262
J 2
(402 3325);
DISPLAY 0.872340 (402 3325);
PAINT GREEN (402 3325);
DISPLAY INVISIBLE (402 3325);
FORCEADD TAP..1
R 2
(400 3425);
FORCEPROP 3 LASTPIN (450 3425) SIG_NAME P5E_CPU0_PE4_RX_DP<5>
J 0
(460 3435);
DISPLAY 0.659574 (460 3435);
PAINT MONO (460 3435);
DISPLAY INVISIBLE (460 3435);
FORCEPROP 1 LASTPIN (450 3425) BN 5
J 2
(462 3433);
DISPLAY 0.680851 (462 3433);
PAINT GREEN (462 3433);
FORCEPROP 2 LAST CDS_LIB standard
J 0
(400 3425);
DISPLAY INVISIBLE (400 3425);
FORCEPROP 1 LAST BODY_TYPE PLUMBING
J 2
(400 3475);
DISPLAY 0.872340 (400 3475);
PAINT GREEN (400 3475);
DISPLAY INVISIBLE (400 3475);
FORCEPROP 1 LAST HDL_TAP TRUE
J 2
(75 3300);
DISPLAY 0.872340 (75 3300);
DISPLAY INVISIBLE (75 3300);
FORCEPROP 1 LAST PATH I263
J 2
(402 3425);
DISPLAY 0.872340 (402 3425);
PAINT GREEN (402 3425);
DISPLAY INVISIBLE (402 3425);
FORCEADD TAP..1
R 2
(400 3475);
FORCEPROP 3 LASTPIN (450 3475) SIG_NAME P5E_CPU0_PE4_RX_DP<6>
J 0
(460 3485);
DISPLAY 0.659574 (460 3485);
PAINT MONO (460 3485);
DISPLAY INVISIBLE (460 3485);
FORCEPROP 1 LASTPIN (450 3475) BN 6
J 2
(462 3483);
DISPLAY 0.680851 (462 3483);
PAINT GREEN (462 3483);
FORCEPROP 2 LAST CDS_LIB standard
J 0
(400 3475);
DISPLAY INVISIBLE (400 3475);
FORCEPROP 1 LAST BODY_TYPE PLUMBING
J 2
(400 3525);
DISPLAY 0.872340 (400 3525);
PAINT GREEN (400 3525);
DISPLAY INVISIBLE (400 3525);
FORCEPROP 1 LAST HDL_TAP TRUE
J 2
(75 3350);
DISPLAY 0.872340 (75 3350);
DISPLAY INVISIBLE (75 3350);
FORCEPROP 1 LAST PATH I264
J 2
(402 3475);
DISPLAY 0.872340 (402 3475);
PAINT GREEN (402 3475);
DISPLAY INVISIBLE (402 3475);
FORCEADD TAP..1
R 2
(400 3525);
FORCEPROP 3 LASTPIN (450 3525) SIG_NAME P5E_CPU0_PE4_RX_DP<7>
J 0
(460 3535);
DISPLAY 0.659574 (460 3535);
PAINT MONO (460 3535);
DISPLAY INVISIBLE (460 3535);
FORCEPROP 1 LASTPIN (450 3525) BN 7
J 2
(462 3533);
DISPLAY 0.680851 (462 3533);
PAINT GREEN (462 3533);
FORCEPROP 2 LAST CDS_LIB standard
J 0
(400 3525);
DISPLAY INVISIBLE (400 3525);
FORCEPROP 1 LAST BODY_TYPE PLUMBING
J 2
(400 3575);
DISPLAY 0.872340 (400 3575);
PAINT GREEN (400 3575);
DISPLAY INVISIBLE (400 3575);
FORCEPROP 1 LAST HDL_TAP TRUE
J 2
(75 3400);
DISPLAY 0.872340 (75 3400);
DISPLAY INVISIBLE (75 3400);
FORCEPROP 1 LAST PATH I265
J 2
(402 3525);
DISPLAY 0.872340 (402 3525);
PAINT GREEN (402 3525);
DISPLAY INVISIBLE (402 3525);
FORCEADD TAP..1
R 2
(400 3575);
FORCEPROP 3 LASTPIN (450 3575) SIG_NAME P5E_CPU0_PE4_RX_DP<8>
J 0
(460 3585);
DISPLAY 0.659574 (460 3585);
PAINT MONO (460 3585);
DISPLAY INVISIBLE (460 3585);
FORCEPROP 1 LASTPIN (450 3575) BN 8
J 2
(462 3583);
DISPLAY 0.680851 (462 3583);
PAINT GREEN (462 3583);
FORCEPROP 2 LAST CDS_LIB standard
J 0
(400 3575);
DISPLAY INVISIBLE (400 3575);
FORCEPROP 1 LAST BODY_TYPE PLUMBING
J 2
(400 3625);
DISPLAY 0.872340 (400 3625);
PAINT GREEN (400 3625);
DISPLAY INVISIBLE (400 3625);
FORCEPROP 1 LAST HDL_TAP TRUE
J 2
(75 3450);
DISPLAY 0.872340 (75 3450);
DISPLAY INVISIBLE (75 3450);
FORCEPROP 1 LAST PATH I266
J 2
(402 3575);
DISPLAY 0.872340 (402 3575);
PAINT GREEN (402 3575);
DISPLAY INVISIBLE (402 3575);
FORCEADD TAP..1
R 2
(400 3625);
FORCEPROP 3 LASTPIN (450 3625) SIG_NAME P5E_CPU0_PE4_RX_DP<9>
J 0
(460 3635);
DISPLAY 0.659574 (460 3635);
PAINT MONO (460 3635);
DISPLAY INVISIBLE (460 3635);
FORCEPROP 1 LASTPIN (450 3625) BN 9
J 2
(462 3633);
DISPLAY 0.680851 (462 3633);
PAINT GREEN (462 3633);
FORCEPROP 2 LAST CDS_LIB standard
J 0
(400 3625);
DISPLAY INVISIBLE (400 3625);
FORCEPROP 1 LAST BODY_TYPE PLUMBING
J 2
(400 3675);
DISPLAY 0.872340 (400 3675);
PAINT GREEN (400 3675);
DISPLAY INVISIBLE (400 3675);
FORCEPROP 1 LAST HDL_TAP TRUE
J 2
(75 3500);
DISPLAY 0.872340 (75 3500);
DISPLAY INVISIBLE (75 3500);
FORCEPROP 1 LAST PATH I267
J 2
(402 3625);
DISPLAY 0.872340 (402 3625);
PAINT GREEN (402 3625);
DISPLAY INVISIBLE (402 3625);
FORCEADD TAP..1
R 2
(400 3675);
FORCEPROP 3 LASTPIN (450 3675) SIG_NAME P5E_CPU0_PE4_RX_DP<10>
J 0
(460 3685);
DISPLAY 0.659574 (460 3685);
PAINT MONO (460 3685);
DISPLAY INVISIBLE (460 3685);
FORCEPROP 1 LASTPIN (450 3675) BN 10
J 2
(462 3683);
DISPLAY 0.680851 (462 3683);
PAINT GREEN (462 3683);
FORCEPROP 2 LAST CDS_LIB standard
J 0
(400 3675);
DISPLAY INVISIBLE (400 3675);
FORCEPROP 1 LAST BODY_TYPE PLUMBING
J 2
(400 3725);
DISPLAY 0.872340 (400 3725);
PAINT GREEN (400 3725);
DISPLAY INVISIBLE (400 3725);
FORCEPROP 1 LAST HDL_TAP TRUE
J 2
(75 3550);
DISPLAY 0.872340 (75 3550);
DISPLAY INVISIBLE (75 3550);
FORCEPROP 1 LAST PATH I268
J 2
(402 3675);
DISPLAY 0.872340 (402 3675);
PAINT GREEN (402 3675);
DISPLAY INVISIBLE (402 3675);
FORCEADD TAP..1
R 2
(400 3725);
FORCEPROP 3 LASTPIN (450 3725) SIG_NAME P5E_CPU0_PE4_RX_DP<11>
J 0
(460 3735);
DISPLAY 0.659574 (460 3735);
PAINT MONO (460 3735);
DISPLAY INVISIBLE (460 3735);
FORCEPROP 1 LASTPIN (450 3725) BN 11
J 2
(462 3733);
DISPLAY 0.680851 (462 3733);
PAINT GREEN (462 3733);
FORCEPROP 2 LAST CDS_LIB standard
J 0
(400 3725);
DISPLAY INVISIBLE (400 3725);
FORCEPROP 1 LAST BODY_TYPE PLUMBING
J 2
(400 3775);
DISPLAY 0.872340 (400 3775);
PAINT GREEN (400 3775);
DISPLAY INVISIBLE (400 3775);
FORCEPROP 1 LAST HDL_TAP TRUE
J 2
(75 3600);
DISPLAY 0.872340 (75 3600);
DISPLAY INVISIBLE (75 3600);
FORCEPROP 1 LAST PATH I269
J 2
(402 3725);
DISPLAY 0.872340 (402 3725);
PAINT GREEN (402 3725);
DISPLAY INVISIBLE (402 3725);
FORCEADD TAP..1
R 2
(400 3775);
FORCEPROP 3 LASTPIN (450 3775) SIG_NAME P5E_CPU0_PE4_RX_DP<12>
J 0
(460 3785);
DISPLAY 0.659574 (460 3785);
PAINT MONO (460 3785);
DISPLAY INVISIBLE (460 3785);
FORCEPROP 1 LASTPIN (450 3775) BN 12
J 2
(462 3783);
DISPLAY 0.680851 (462 3783);
PAINT GREEN (462 3783);
FORCEPROP 2 LAST CDS_LIB standard
J 0
(400 3775);
DISPLAY INVISIBLE (400 3775);
FORCEPROP 1 LAST BODY_TYPE PLUMBING
J 2
(400 3825);
DISPLAY 0.872340 (400 3825);
PAINT GREEN (400 3825);
DISPLAY INVISIBLE (400 3825);
FORCEPROP 1 LAST HDL_TAP TRUE
J 2
(75 3650);
DISPLAY 0.872340 (75 3650);
DISPLAY INVISIBLE (75 3650);
FORCEPROP 1 LAST PATH I270
J 2
(402 3775);
DISPLAY 0.872340 (402 3775);
PAINT GREEN (402 3775);
DISPLAY INVISIBLE (402 3775);
FORCEADD TAP..1
R 2
(400 3875);
FORCEPROP 3 LASTPIN (450 3875) SIG_NAME P5E_CPU0_PE4_RX_DP<14>
J 0
(460 3885);
DISPLAY 0.659574 (460 3885);
PAINT MONO (460 3885);
DISPLAY INVISIBLE (460 3885);
FORCEPROP 1 LASTPIN (450 3875) BN 14
J 2
(462 3883);
DISPLAY 0.680851 (462 3883);
PAINT GREEN (462 3883);
FORCEPROP 2 LAST CDS_LIB standard
J 0
(400 3875);
DISPLAY INVISIBLE (400 3875);
FORCEPROP 1 LAST BODY_TYPE PLUMBING
J 2
(400 3925);
DISPLAY 0.872340 (400 3925);
PAINT GREEN (400 3925);
DISPLAY INVISIBLE (400 3925);
FORCEPROP 1 LAST HDL_TAP TRUE
J 2
(75 3750);
DISPLAY 0.872340 (75 3750);
DISPLAY INVISIBLE (75 3750);
FORCEPROP 1 LAST PATH I271
J 2
(402 3875);
DISPLAY 0.872340 (402 3875);
PAINT GREEN (402 3875);
DISPLAY INVISIBLE (402 3875);
FORCEADD TAP..1
R 2
(400 3825);
FORCEPROP 3 LASTPIN (450 3825) SIG_NAME P5E_CPU0_PE4_RX_DP<13>
J 0
(460 3835);
DISPLAY 0.659574 (460 3835);
PAINT MONO (460 3835);
DISPLAY INVISIBLE (460 3835);
FORCEPROP 1 LASTPIN (450 3825) BN 13
J 2
(462 3833);
DISPLAY 0.680851 (462 3833);
PAINT GREEN (462 3833);
FORCEPROP 2 LAST CDS_LIB standard
J 0
(400 3825);
DISPLAY INVISIBLE (400 3825);
FORCEPROP 1 LAST BODY_TYPE PLUMBING
J 2
(400 3875);
DISPLAY 0.872340 (400 3875);
PAINT GREEN (400 3875);
DISPLAY INVISIBLE (400 3875);
FORCEPROP 1 LAST HDL_TAP TRUE
J 2
(75 3700);
DISPLAY 0.872340 (75 3700);
DISPLAY INVISIBLE (75 3700);
FORCEPROP 1 LAST PATH I272
J 2
(402 3825);
DISPLAY 0.872340 (402 3825);
PAINT GREEN (402 3825);
DISPLAY INVISIBLE (402 3825);
FORCEADD TAP..1
R 2
(400 3925);
FORCEPROP 3 LASTPIN (450 3925) SIG_NAME P5E_CPU0_PE4_RX_DP<15>
J 0
(460 3935);
DISPLAY 0.659574 (460 3935);
PAINT MONO (460 3935);
DISPLAY INVISIBLE (460 3935);
FORCEPROP 1 LASTPIN (450 3925) BN 15
J 2
(462 3933);
DISPLAY 0.680851 (462 3933);
PAINT GREEN (462 3933);
FORCEPROP 2 LAST CDS_LIB standard
J 0
(400 3925);
DISPLAY INVISIBLE (400 3925);
FORCEPROP 1 LAST BODY_TYPE PLUMBING
J 2
(400 3975);
DISPLAY 0.872340 (400 3975);
PAINT GREEN (400 3975);
DISPLAY INVISIBLE (400 3975);
FORCEPROP 1 LAST HDL_TAP TRUE
J 2
(75 3800);
DISPLAY 0.872340 (75 3800);
DISPLAY INVISIBLE (75 3800);
FORCEPROP 1 LAST PATH I273
J 2
(402 3925);
DISPLAY 0.872340 (402 3925);
PAINT GREEN (402 3925);
DISPLAY INVISIBLE (402 3925);
FORCEADD TAP..1
R 2
(400 2475);
FORCEPROP 3 LASTPIN (450 2475) SIG_NAME P5E_CPU0_PE4_RX_DN<3>
J 0
(460 2485);
DISPLAY 0.659574 (460 2485);
PAINT MONO (460 2485);
DISPLAY INVISIBLE (460 2485);
FORCEPROP 1 LASTPIN (450 2475) BN 3
J 2
(462 2483);
DISPLAY 0.680851 (462 2483);
PAINT GREEN (462 2483);
FORCEPROP 2 LAST CDS_LIB standard
J 0
(400 2475);
DISPLAY INVISIBLE (400 2475);
FORCEPROP 1 LAST BODY_TYPE PLUMBING
J 2
(400 2525);
DISPLAY 0.872340 (400 2525);
PAINT GREEN (400 2525);
DISPLAY INVISIBLE (400 2525);
FORCEPROP 1 LAST HDL_TAP TRUE
J 2
(75 2350);
DISPLAY 0.872340 (75 2350);
DISPLAY INVISIBLE (75 2350);
FORCEPROP 1 LAST PATH I274
J 2
(402 2475);
DISPLAY 0.872340 (402 2475);
PAINT GREEN (402 2475);
DISPLAY INVISIBLE (402 2475);
FORCEADD QUANTA_TITLE_BLOCK_C..1
(6700 -1575);
FORCEPROP 0 LAST CDS_CON_LAST_MODIFIED Fri Aug 25 14:00:16 2023
J 0
(4815 -1560);
PAINT MONO (4815 -1560);
DISPLAY INVISIBLE (4815 -1560);
FORCEPROP 1 LAST CUSTOM_TXT_CDS <CON_LAST_MODIFIED>
J 0
(4815 -1560);
DISPLAY 0.978723 (4815 -1560);
FORCEPROP 2 LAST CUSTOM_TXT_CDS <XR_PAGE_TITLE>
J 0
(-1190 3675);
DISPLAY 0.638298 (-1190 3675);
PAINT PINK (-1190 3675);
DISPLAY INVISIBLE (-1190 3675);
FORCEPROP 2 LAST CUSTOM_TXT_CDS <Q_NUMBER>
J 0
(5297 -1472);
DISPLAY 1.212766 (5297 -1472);
FORCEPROP 1 LAST CUSTOM_TXT_CDS <NAME_2>
J 0
(3525 -1525);
FORCEPROP 1 LAST CUSTOM_TXT_CDS <NAME_1>
J 0
(3525 -1400);
FORCEPROP 1 LAST CUSTOM_TXT_CDS <Q_PROJ>
J 0
(4318 -1473);
DISPLAY 1.212766 (4318 -1473);
FORCEPROP 1 LAST CUSTOM_TXT_CDS <Q_REV>
J 0
(6516 -1472);
DISPLAY 1.212766 (6516 -1472);
FORCEPROP 1 LAST CUSTOM_TXT_CDS <CON_PAGE_NUM> OF <CON_TOTAL_PAGES>
J 0
(6254 -1557);
DISPLAY 0.978723 (6254 -1557);
FORCEPROP 1 LAST Q_TITLE SPR CPU0 - PCIE PE4 (19 OF 30)
J 0
(-2666 -1549);
DISPLAY 1.957447 (-2666 -1549);
PAINT GREEN (-2666 -1549);
FORCEPROP 1 LAST Q_DEPT 
J 1
(2937 -1526);
DISPLAY 1.957447 (2937 -1526);
PAINT GREEN (2937 -1526);
FORCEPROP 2 LAST PAGE_BORDER TRUE
J 0
(-1190 3675);
DISPLAY 0.638298 (-1190 3675);
PAINT PINK (-1190 3675);
DISPLAY INVISIBLE (-1190 3675);
FORCEPROP 1 LAST CDS_LMAN_SYM_OUTLINE -9475,6775,100,-125
J 0
(6700 -1575);
DISPLAY 0.468085 (6700 -1575);
PAINT GREEN (6700 -1575);
DISPLAY INVISIBLE (6700 -1575);
FORCEPROP 2 LAST CDS_LIB pure_quanta
J 0
(6700 -1575);
PAINT MONO (6700 -1575);
DISPLAY INVISIBLE (6700 -1575);
FORCEPROP 2 LAST CDS_XR_PAGE_TITLE CR-31 : @S9S_MB_2U_LIB.S9S_MB_2U(SCH_1):PAGE31
J 0
(-1190 3675);
DISPLAY 0.638298 (-1190 3675);
PAINT PINK (-1190 3675);
DISPLAY INVISIBLE (-1190 3675);
FORCEPROP 1 LAST COMMENT_BODY TRUE
J 0
(6712 -1588);
DISPLAY 0.978723 (6712 -1588);
PAINT GREEN (6712 -1588);
DISPLAY INVISIBLE (6712 -1588);
WIRE 17 -1 (3875 3200)(3875 3250);
WIRE 17 -1 (3875 3250)(3875 3300);
WIRE 17 -1 (3875 3300)(3875 3350);
WIRE 17 -1 (3875 3350)(3875 3400);
WIRE 17 -1 (3875 3400)(3875 3450);
WIRE 17 -1 (3875 3450)(3875 3500);
WIRE 17 -1 (3875 3500)(3875 3550);
WIRE 17 -1 (3875 3550)(3875 3600);
WIRE 17 -1 (3875 3600)(3875 3650);
WIRE 17 -1 (3875 3650)(3875 3700);
WIRE 17 -1 (3875 3700)(3875 3750);
WIRE 17 -1 (3875 3750)(3875 3800);
WIRE 17 -1 (3875 3800)(3875 3850);
WIRE 17 -1 (3875 3850)(3875 3900);
WIRE 17 -1 (3875 3900)(3875 3950);
WIRE 17 -1 (3875 3950)(4875 3950);
FORCEPROP 2 LAST SIG_NAME P5E_CPU0_PE4_TX_DP<15:0>
J 0
(4015 3960);
DISPLAY 0.680851 (4015 3960);
PAINT WHITE (4015 3960);
WIRE 17 -1 (3875 2350)(3875 2400);
WIRE 17 -1 (3875 2400)(3875 2450);
WIRE 17 -1 (3875 2450)(3875 2500);
WIRE 17 -1 (3875 2500)(3875 2550);
WIRE 17 -1 (3875 2550)(3875 2600);
WIRE 17 -1 (3875 2600)(3875 2650);
WIRE 17 -1 (3875 2650)(3875 2700);
WIRE 17 -1 (3875 2700)(3875 2750);
WIRE 17 -1 (3875 2750)(3875 2800);
WIRE 17 -1 (3875 2800)(3875 2850);
WIRE 17 -1 (3875 2850)(3875 2900);
WIRE 17 -1 (3875 2900)(3875 2950);
WIRE 17 -1 (3875 2950)(3875 3000);
WIRE 17 -1 (3875 3000)(3875 3050);
WIRE 17 -1 (3875 3050)(3875 3100);
WIRE 17 -1 (3875 3100)(4875 3100);
FORCEPROP 2 LAST SIG_NAME P5E_CPU0_PE4_TX_DN<15:0>
J 0
(4015 3110);
DISPLAY 0.680851 (4015 3110);
PAINT WHITE (4015 3110);
WIRE 17 -1 (350 3200)(350 3250);
WIRE 17 -1 (350 3250)(350 3300);
WIRE 17 -1 (350 3300)(350 3350);
WIRE 17 -1 (350 3350)(350 3400);
WIRE 17 -1 (350 3400)(350 3450);
WIRE 17 -1 (350 3450)(350 3500);
WIRE 17 -1 (350 3500)(350 3550);
WIRE 17 -1 (350 3550)(350 3600);
WIRE 17 -1 (350 3600)(350 3650);
WIRE 17 -1 (350 3650)(350 3700);
WIRE 17 -1 (350 3700)(350 3750);
WIRE 17 -1 (350 3750)(350 3800);
WIRE 17 -1 (350 3800)(350 3850);
WIRE 17 -1 (350 3850)(350 3900);
WIRE 17 -1 (350 3900)(350 3950);
WIRE 17 -1 (-800 3950)(350 3950);
FORCEPROP 2 LAST SIG_NAME P5E_CPU0_PE4_RX_DP<15:0>
J 0
(-685 3960);
DISPLAY 0.680851 (-685 3960);
PAINT WHITE (-685 3960);
WIRE 17 -1 (350 2350)(350 2400);
WIRE 17 -1 (350 2400)(350 2450);
WIRE 17 -1 (350 2450)(350 2500);
WIRE 17 -1 (350 2500)(350 2550);
WIRE 17 -1 (350 2550)(350 2600);
WIRE 17 -1 (350 2600)(350 2650);
WIRE 17 -1 (350 2650)(350 2700);
WIRE 17 -1 (350 2700)(350 2750);
WIRE 17 -1 (350 2750)(350 2800);
WIRE 17 -1 (350 2800)(350 2850);
WIRE 17 -1 (350 2850)(350 2900);
WIRE 17 -1 (350 2900)(350 2950);
WIRE 17 -1 (350 2950)(350 3000);
WIRE 17 -1 (350 3000)(350 3050);
WIRE 17 -1 (350 3050)(350 3100);
WIRE 17 -1 (-800 3100)(350 3100);
FORCEPROP 2 LAST SIG_NAME P5E_CPU0_PE4_RX_DN<15:0>
J 0
(-685 3110);
DISPLAY 0.680851 (-685 3110);
PAINT WHITE (-685 3110);
WIRE 16 -1 (450 3075)(900 3075);
WIRE 16 -1 (450 3025)(900 3025);
WIRE 16 -1 (450 2975)(900 2975);
WIRE 16 -1 (450 2925)(900 2925);
WIRE 16 -1 (450 2875)(900 2875);
WIRE 16 -1 (450 2825)(900 2825);
WIRE 16 -1 (450 2775)(900 2775);
WIRE 16 -1 (450 2725)(900 2725);
WIRE 16 -1 (450 2675)(900 2675);
WIRE 16 -1 (450 2625)(900 2625);
WIRE 16 -1 (450 2575)(900 2575);
WIRE 16 -1 (450 2525)(900 2525);
WIRE 16 -1 (450 2475)(900 2475);
WIRE 16 -1 (450 2425)(900 2425);
WIRE 16 -1 (450 2375)(900 2375);
WIRE 16 -1 (450 2325)(900 2325);
WIRE 16 -1 (450 3925)(900 3925);
WIRE 16 -1 (450 3875)(900 3875);
WIRE 16 -1 (450 3825)(900 3825);
WIRE 16 -1 (450 3775)(900 3775);
WIRE 16 -1 (450 3725)(900 3725);
WIRE 16 -1 (450 3675)(900 3675);
WIRE 16 -1 (450 3625)(900 3625);
WIRE 16 -1 (450 3575)(900 3575);
WIRE 16 -1 (450 3525)(900 3525);
WIRE 16 -1 (450 3475)(900 3475);
WIRE 16 -1 (450 3425)(900 3425);
WIRE 16 -1 (450 3375)(900 3375);
WIRE 16 -1 (450 3325)(900 3325);
WIRE 16 -1 (450 3275)(900 3275);
WIRE 16 -1 (450 3225)(900 3225);
WIRE 16 -1 (450 3175)(900 3175);
WIRE 16 -1 (3300 3075)(3775 3075);
WIRE 16 -1 (3300 3025)(3775 3025);
WIRE 16 -1 (3300 2975)(3775 2975);
WIRE 16 -1 (3300 2925)(3775 2925);
WIRE 16 -1 (3300 2875)(3775 2875);
WIRE 16 -1 (3300 2825)(3775 2825);
WIRE 16 -1 (3300 2775)(3775 2775);
WIRE 16 -1 (3300 2725)(3775 2725);
WIRE 16 -1 (3300 2675)(3775 2675);
WIRE 16 -1 (3300 2625)(3775 2625);
WIRE 16 -1 (3300 2575)(3775 2575);
WIRE 16 -1 (3300 2525)(3775 2525);
WIRE 16 -1 (3300 2475)(3775 2475);
WIRE 16 -1 (3300 2425)(3775 2425);
WIRE 16 -1 (3300 2375)(3775 2375);
WIRE 16 -1 (3300 2325)(3775 2325);
WIRE 16 -1 (3300 3925)(3775 3925);
WIRE 16 -1 (3300 3875)(3775 3875);
WIRE 16 -1 (3300 3825)(3775 3825);
WIRE 16 -1 (3300 3775)(3775 3775);
WIRE 16 -1 (3300 3725)(3775 3725);
WIRE 16 -1 (3300 3675)(3775 3675);
WIRE 16 -1 (3300 3625)(3775 3625);
WIRE 16 -1 (3300 3575)(3775 3575);
WIRE 16 -1 (3300 3525)(3775 3525);
WIRE 16 -1 (3300 3475)(3775 3475);
WIRE 16 -1 (3300 3425)(3775 3425);
WIRE 16 -1 (3300 3375)(3775 3375);
WIRE 16 -1 (3300 3325)(3775 3325);
WIRE 16 -1 (3300 3275)(3775 3275);
WIRE 16 -1 (3300 3225)(3775 3225);
WIRE 16 -1 (3300 3175)(3775 3175);
FORCENOTE
20210818 MODIFY FOR GT
(800 4700) 0;
DISPLAY LEFT (800 4700);
DISPLAY 2.510638 (800 4700);
PAINT PINK (800 4700);
QUIT
